# Altium SchDoc records: ZED-F9T.SchDoc
|HEADER=Protel for Windows - Schematic Capture Binary File Version 5.0|Weight=2113|MinorVersion=4
|RECORD=31|FontIdCount=16|Size1=10|FontName1=Times New Roman|Size2=10|Underline2=T|FontName2=Times New Roman|Size3=14|FontName3=Arial Narrow|Size4=12|FontName4=Arial|Size5=8|FontName5=Arial|Size6=10|FontName6=Arial|Size7=14|FontName7=Arial|Size8=9|FontName8=Arial|Size9=9|FontName9=Arial Narrow|Size10=22|FontName10=Arial Narrow|Size11=6|Rotation11=90|FontName11=Arial|Size12=6|FontName12=Arial|Size13=9|Rotation13=90|FontName13=Arial|Size14=24|FontName14=Arial|Size15=14|FontName15=Times New Roman|Size16=10|FontName16=Verdana|UseMBCS=T|IsBOC=T|HotSpotGridOn=T|HotSpotGridSize=4|SheetStyle=5|SystemFont=6|BorderOn=T|TitleBlockOn=T|SheetNumberSpaceSize=12|AreaColor=16317695|SnapGridOn=T|SnapGridSize=10|VisibleGridOn=T|VisibleGridSize=10|CustomX=1700|CustomY=1100|CustomXZones=8|CustomYZones=6|CustomMarginWidth=20|Display_Unit=0|ReferenceZoneStyle=1
|RECORD=39|IsNotAccesible=T|OwnerPartId=-1|FileName=C:\Users\<user>\Documents\Altium\AD22\Templates\ANSI B Landscape.SchDot
|RECORD=4|OwnerIndex=1|OwnerPartId=-1|Location.X=1345|Location.Y=1068|FontID=9|Text=REVISION
|RECORD=4|OwnerIndex=1|IndexInSheet=1|OwnerPartId=-1|Location.X=1460|Location.Y=1068|FontID=9|Text=DESCRIPTION
|RECORD=4|OwnerIndex=1|IndexInSheet=2|OwnerPartId=-1|Location.X=1592|Location.Y=1068|FontID=9|Text=DATE
|RECORD=4|OwnerIndex=1|IndexInSheet=3|OwnerPartId=-1|Location.X=1633|Location.Y=1068|FontID=9|Text=APPROVED
|RECORD=6|OwnerIndex=1|IndexInSheet=4|OwnerPartId=-1|LocationCount=3|X1=1340|Y1=1080|X2=1340|Y2=1065|X3=1680|Y3=1065
|RECORD=6|OwnerIndex=1|IndexInSheet=5|OwnerPartId=-1|LocationCount=2|X1=1380|Y1=1080|X2=1380|Y2=1065
|RECORD=6|OwnerIndex=1|IndexInSheet=6|OwnerPartId=-1|LocationCount=2|X1=1620|Y1=1080|X2=1620|Y2=1065
|RECORD=6|OwnerIndex=1|IndexInSheet=7|OwnerPartId=-1|LocationCount=2|X1=1580|Y1=1080|X2=1580|Y2=1065
|RECORD=6|OwnerIndex=1|IndexInSheet=8|OwnerPartId=-1|LocationCount=3|X1=1340|Y1=1070|X2=1340|Y2=1050|X3=1680|Y3=1050
|RECORD=6|OwnerIndex=1|IndexInSheet=9|OwnerPartId=-1|LocationCount=2|X1=1380|Y1=1065|X2=1380|Y2=1050
|RECORD=6|OwnerIndex=1|IndexInSheet=10|OwnerPartId=-1|LocationCount=2|X1=1580|Y1=1065|X2=1580|Y2=1050
|RECORD=6|OwnerIndex=1|IndexInSheet=11|OwnerPartId=-1|LocationCount=2|X1=1620|Y1=1065|X2=1620|Y2=1050
|RECORD=6|OwnerIndex=1|IndexInSheet=12|OwnerPartId=-1|LineWidth=1|LocationCount=2|X1=1695|Y1=184|X2=1700|Y2=184
|RECORD=4|OwnerIndex=1|IndexInSheet=13|OwnerPartId=-1|Location.X=1689|Location.Y=189|Orientation=3|FontID=11|Text=REV.
|RECORD=4|OwnerIndex=1|IndexInSheet=14|OwnerPartId=-1|Location.X=1689|Location.Y=174|Orientation=3|FontID=11|Text=SHT.
|RECORD=4|OwnerIndex=1|IndexInSheet=15|OwnerPartId=-1|Location.X=1695|Location.Y=259|Orientation=3|Justification=6|FontID=11|Text=DWG. NO.|IsMirrored=T
|RECORD=4|OwnerIndex=1|IndexInSheet=16|OwnerPartId=-1|Location.X=1680|Location.Y=258|Orientation=3|FontID=13|Text==DOC_NO_SCH_DWG
|RECORD=4|OwnerIndex=1|IndexInSheet=17|OwnerPartId=-1|Location.X=1680|Location.Y=182|Orientation=3|Justification=1|FontID=13|Text==ItemRevision
|RECORD=4|OwnerIndex=1|IndexInSheet=18|OwnerPartId=-1|Location.X=1680|Location.Y=169|Orientation=3|Justification=1|FontID=13|Text==SheetNumber
|RECORD=6|OwnerIndex=1|IndexInSheet=19|OwnerPartId=-1|LineWidth=1|LocationCount=3|X1=1695|Y1=160|X2=1695|Y2=260|X3=1680|Y3=260
|RECORD=6|OwnerIndex=1|IndexInSheet=20|OwnerPartId=-1|LocationCount=2|X1=1695|Y1=175|X2=1680|Y2=175
|RECORD=6|OwnerIndex=1|IndexInSheet=21|OwnerPartId=-1|LocationCount=2|X1=1695|Y1=190|X2=1680|Y2=190
|RECORD=6|OwnerIndex=1|IndexInSheet=22|OwnerPartId=-1|LineWidth=1|LocationCount=2|X1=1695|Y1=160|X2=1680|Y2=160
|RECORD=4|OwnerIndex=1|IndexInSheet=23|OwnerPartId=-1|Location.X=1312|Location.Y=1080|FontID=12|Text=REV.
|RECORD=4|OwnerIndex=1|IndexInSheet=24|OwnerPartId=-1|Location.X=1327|Location.Y=1080|FontID=12|Text=SHT.
|RECORD=4|OwnerIndex=1|IndexInSheet=25|OwnerPartId=-1|Location.X=1283|Location.Y=1086|Justification=6|FontID=12|Text=DWG. NO.|IsMirrored=T
|RECORD=4|OwnerIndex=1|IndexInSheet=26|OwnerPartId=-1|Location.X=1247|Location.Y=1085|FontID=8|Text==DOC_NO_SCH_DWG
|RECORD=4|OwnerIndex=1|IndexInSheet=27|OwnerPartId=-1|Location.X=1317|Location.Y=1085|Justification=1|FontID=8|Text==ItemRevision
|RECORD=4|OwnerIndex=1|IndexInSheet=28|OwnerPartId=-1|Location.X=1332|Location.Y=1085|Justification=1|FontID=8|Text==SheetNumber
|RECORD=6|OwnerIndex=1|IndexInSheet=29|OwnerPartId=-1|LineWidth=1|LocationCount=3|X1=1340|Y1=1095|X2=1240|Y2=1095|X3=1240|Y3=1080
|RECORD=6|OwnerIndex=1|IndexInSheet=30|OwnerPartId=-1|LocationCount=2|X1=1325|Y1=1095|X2=1325|Y2=1080
|RECORD=6|OwnerIndex=1|IndexInSheet=31|OwnerPartId=-1|LocationCount=2|X1=1310|Y1=1095|X2=1310|Y2=1080
|RECORD=6|OwnerIndex=1|IndexInSheet=32|OwnerPartId=-1|LineWidth=1|LocationCount=2|X1=1340|Y1=1095|X2=1340|Y2=1080
|RECORD=7|OwnerIndex=1|IndexInSheet=33|OwnerPartId=-1|IsSolid=T|LocationCount=3|X1=850|Y1=1080|X2=855|Y2=1090|X3=845|Y3=1090
|RECORD=7|OwnerIndex=1|IndexInSheet=34|OwnerPartId=-1|IsSolid=T|LocationCount=3|X1=850|Y1=20|X2=845|Y2=10|X3=855|Y3=10
|RECORD=7|OwnerIndex=1|IndexInSheet=35|OwnerPartId=-1|IsSolid=T|LocationCount=3|X1=1680|Y1=550|X2=1690|Y2=545|X3=1690|Y3=555
|RECORD=28|OwnerIndex=1|IndexInSheet=36|OwnerPartId=-1|UnionIndex=1|Location.X=25|Location.Y=1033|Corner.X=298|Corner.Y=1075|AreaColor=16777215|FontID=6|Alignment=1|WordWrap=T|Text=THIS DOCUMENT AND THE DATA DISCLOSED HEREIN OR HEREWITH IS THE PROPERTY OF ALTIUM LIMITED AND MAY BE FREELY DISTRIBUTED IN WHOLE. NO RIGHTS ARE RESERVED OR EXPRESS OR IMPLIED WARANTEE GIVEN.|TextMargin_Frac=5
|RECORD=6|OwnerIndex=1|IndexInSheet=37|OwnerPartId=-1|UnionIndex=1|LineWidth=1|LocationCount=5|X1=300|Y1=1080|X2=20|Y2=1080|X3=20|Y3=1032|X4=300|Y4=1032|X5=300|Y5=1080
|RECORD=13|OwnerIndex=1|IndexInSheet=38|OwnerPartId=-1|Location.Y=1100|Corner.X=1699|Corner.X_Frac=83312|Corner.Y=1100|LineWidth=1
|RECORD=13|OwnerIndex=1|IndexInSheet=39|OwnerPartId=-1|Location.X=1699|Location.X_Frac=83312|Location.Y=1100|Corner.X=1699|Corner.X_Frac=83312|Corner.Y_Frac=16696|LineWidth=1
|RECORD=13|OwnerIndex=1|IndexInSheet=40|OwnerPartId=-1|Location.X=1699|Location.X_Frac=83312|Location.Y_Frac=16696|Corner.Y_Frac=16696|LineWidth=1
|RECORD=13|OwnerIndex=1|IndexInSheet=41|OwnerPartId=-1|Location.Y_Frac=16696|Corner.Y=1100|LineWidth=1
|RECORD=13|OwnerIndex=1|IndexInSheet=42|OwnerPartId=-1|Location.X=20|Location.X_Frac=12|Location.Y=1079|Location.Y_Frac=99791|Corner.X=1679|Corner.X_Frac=83296|Corner.Y=1079|Corner.Y_Frac=99791|LineWidth=1
|RECORD=13|OwnerIndex=1|IndexInSheet=43|OwnerPartId=-1|Location.X=1679|Location.X_Frac=83296|Location.Y=1079|Location.Y_Frac=99791|Corner.X=1679|Corner.X_Frac=83296|Corner.Y=20|Corner.Y_Frac=16904|LineWidth=1
|RECORD=13|OwnerIndex=1|IndexInSheet=44|OwnerPartId=-1|Location.X=1679|Location.X_Frac=83296|Location.Y=20|Location.Y_Frac=16904|Corner.X=20|Corner.X_Frac=12|Corner.Y=20|Corner.Y_Frac=16904|LineWidth=1
|RECORD=13|OwnerIndex=1|IndexInSheet=45|OwnerPartId=-1|Location.X=20|Location.X_Frac=12|Location.Y=20|Location.Y_Frac=16904|Corner.X=20|Corner.X_Frac=12|Corner.Y=1079|Corner.Y_Frac=99791|LineWidth=1
|RECORD=13|OwnerIndex=1|IndexInSheet=46|OwnerPartId=-1|Location.X=1487|Location.X_Frac=50000|Location.Y=20|Corner.X=1487|Corner.X_Frac=50000|LineWidth=1
|RECORD=13|OwnerIndex=1|IndexInSheet=47|OwnerPartId=-1|Location.X=1487|Location.X_Frac=50000|Location.Y=1080|Corner.X=1487|Corner.X_Frac=50000|Corner.Y=1100|LineWidth=1
|RECORD=13|OwnerIndex=1|IndexInSheet=48|OwnerPartId=-1|Location.X=1275|Location.Y=20|Corner.X=1275|LineWidth=1
|RECORD=13|OwnerIndex=1|IndexInSheet=49|OwnerPartId=-1|Location.X=1275|Location.Y=1095|Corner.X=1275|Corner.Y=1100|LineWidth=1
|RECORD=13|OwnerIndex=1|IndexInSheet=50|OwnerPartId=-1|Location.X=1062|Location.X_Frac=50000|Location.Y=20|Corner.X=1062|Corner.X_Frac=50000|LineWidth=1
|RECORD=13|OwnerIndex=1|IndexInSheet=51|OwnerPartId=-1|Location.X=1062|Location.X_Frac=50000|Location.Y=1080|Corner.X=1062|Corner.X_Frac=50000|Corner.Y=1100|LineWidth=1
|RECORD=13|OwnerIndex=1|IndexInSheet=52|OwnerPartId=-1|Location.X=850|Location.Y=20|Corner.X=850|LineWidth=1
|RECORD=13|OwnerIndex=1|IndexInSheet=53|OwnerPartId=-1|Location.X=850|Location.Y=1080|Corner.X=850|Corner.Y=1100|LineWidth=1
|RECORD=13|OwnerIndex=1|IndexInSheet=54|OwnerPartId=-1|Location.X=637|Location.X_Frac=50000|Location.Y=20|Corner.X=637|Corner.X_Frac=50000|LineWidth=1
|RECORD=13|OwnerIndex=1|IndexInSheet=55|OwnerPartId=-1|Location.X=637|Location.X_Frac=50000|Location.Y=1080|Corner.X=637|Corner.X_Frac=50000|Corner.Y=1100|LineWidth=1
|RECORD=13|OwnerIndex=1|IndexInSheet=56|OwnerPartId=-1|Location.X=425|Location.Y=20|Corner.X=425|LineWidth=1
|RECORD=13|OwnerIndex=1|IndexInSheet=57|OwnerPartId=-1|Location.X=425|Location.Y=1080|Corner.X=425|Corner.Y=1100|LineWidth=1
|RECORD=13|OwnerIndex=1|IndexInSheet=58|OwnerPartId=-1|Location.X=212|Location.X_Frac=50000|Location.Y=20|Corner.X=212|Corner.X_Frac=50000|LineWidth=1
|RECORD=13|OwnerIndex=1|IndexInSheet=59|OwnerPartId=-1|Location.X=212|Location.X_Frac=50000|Location.Y=1080|Corner.X=212|Corner.X_Frac=50000|Corner.Y=1100|LineWidth=1
|RECORD=13|OwnerIndex=1|IndexInSheet=60|OwnerPartId=-1|Location.X=20|Location.Y=916|Location.Y_Frac=66664|Corner.Y=916|Corner.Y_Frac=66664|LineWidth=1
|RECORD=13|OwnerIndex=1|IndexInSheet=61|OwnerPartId=-1|Location.X=1680|Location.Y=916|Location.Y_Frac=66664|Corner.X=1700|Corner.Y=916|Corner.Y_Frac=66664|LineWidth=1
|RECORD=13|OwnerIndex=1|IndexInSheet=62|OwnerPartId=-1|Location.X=20|Location.Y=733|Location.Y_Frac=33328|Corner.Y=733|Corner.Y_Frac=33328|LineWidth=1
|RECORD=13|OwnerIndex=1|IndexInSheet=63|OwnerPartId=-1|Location.X=1680|Location.Y=733|Location.Y_Frac=33328|Corner.X=1700|Corner.Y=733|Corner.Y_Frac=33328|LineWidth=1
|RECORD=13|OwnerIndex=1|IndexInSheet=64|OwnerPartId=-1|Location.X=20|Location.Y=550|Corner.Y=550|LineWidth=1
|RECORD=13|OwnerIndex=1|IndexInSheet=65|OwnerPartId=-1|Location.X=1680|Location.Y=550|Corner.X=1700|Corner.Y=550|LineWidth=1
|RECORD=13|OwnerIndex=1|IndexInSheet=66|OwnerPartId=-1|Location.X=20|Location.Y=366|Location.Y_Frac=66664|Corner.Y=366|Corner.Y_Frac=66664|LineWidth=1
|RECORD=13|OwnerIndex=1|IndexInSheet=67|OwnerPartId=-1|Location.X=1680|Location.Y=366|Location.Y_Frac=66664|Corner.X=1700|Corner.Y=366|Corner.Y_Frac=66664|LineWidth=1
|RECORD=13|OwnerIndex=1|IndexInSheet=68|OwnerPartId=-1|Location.X=20|Location.Y=183|Location.Y_Frac=33330|Corner.Y=183|Corner.Y_Frac=33330|LineWidth=1
|RECORD=7|OwnerIndex=1|IndexInSheet=69|OwnerPartId=-1|IsSolid=T|LocationCount=3|X1=20|Y1=550|X2=10|Y2=545|X3=10|Y3=555
|RECORD=4|OwnerIndex=1|IndexInSheet=70|OwnerPartId=-1|Location.X=1348|Location.Y=71|FontID=14|Text==title
|RECORD=4|OwnerIndex=1|IndexInSheet=71|OwnerPartId=-1|Location.X=1450|Location.Y=40|FontID=3|Text==DOC_NO_SCH_DWG
|RECORD=6|OwnerIndex=1|IndexInSheet=72|OwnerPartId=-1|LocationCount=2|X1=1405|Y1=65|X2=1405|Y2=35
|RECORD=6|OwnerIndex=1|IndexInSheet=73|OwnerPartId=-1|LocationCount=2|X1=1680|Y1=35|X2=1320|Y2=35
|RECORD=6|OwnerIndex=1|IndexInSheet=74|OwnerPartId=-1|LocationCount=2|X1=1650|Y1=65|X2=1650|Y2=35
|RECORD=4|OwnerIndex=1|IndexInSheet=75|OwnerPartId=-1|Location.X=1330|Location.Y=35|FontID=10|Text=B
|RECORD=4|OwnerIndex=1|IndexInSheet=76|OwnerPartId=-1|Location.X=1428|Location.Y=20|FontID=4|Text==DocumentName
|RECORD=4|OwnerIndex=1|IndexInSheet=77|OwnerPartId=-1|Location.X=1615|Location.Y=20|FontID=4|Text==SheetNumber
|RECORD=4|OwnerIndex=1|IndexInSheet=78|OwnerPartId=-1|Location.X=1655|Location.Y=20|FontID=4|Text==SheetTotal
|RECORD=4|OwnerIndex=1|IndexInSheet=79|OwnerPartId=-1|Location.X=1323|Location.Y=100|Justification=3|FontID=5|Text=TITLE
|RECORD=4|OwnerIndex=1|IndexInSheet=80|OwnerPartId=-1|Location.X=1328|Location.Y=60|Justification=3|FontID=5|Text=SIZE
|RECORD=4|OwnerIndex=1|IndexInSheet=81|OwnerPartId=-1|Location.X=1407|Location.Y=60|Justification=3|FontID=5|Text=DWG NO.
|RECORD=4|OwnerIndex=1|IndexInSheet=82|OwnerPartId=-1|Location.X=1387|Location.Y=30|Justification=3|FontID=5|Text=FILE NAME
|RECORD=4|OwnerIndex=1|IndexInSheet=83|OwnerPartId=-1|Location.X=1582|Location.Y=30|Justification=3|FontID=5|Text=SHEET
|RECORD=4|OwnerIndex=1|IndexInSheet=84|OwnerPartId=-1|Location.X=1640|Location.Y=30|Justification=3|FontID=5|Text=OF
|RECORD=4|OwnerIndex=1|IndexInSheet=85|OwnerPartId=-1|Location.X=1657|Location.Y=60|Justification=3|FontID=5|Text=REV
|RECORD=6|OwnerIndex=1|IndexInSheet=86|OwnerPartId=-1|LocationCount=2|X1=1385|Y1=35|X2=1385|Y2=20
|RECORD=4|OwnerIndex=1|IndexInSheet=87|OwnerPartId=-1|Location.X=1322|Location.Y=30|Justification=3|FontID=5|Text=SCALE:
|RECORD=4|OwnerIndex=1|IndexInSheet=88|OwnerPartId=-1|Location.X=1349|Location.Y=20|FontID=4|Text==SCH_SCALE
|RECORD=6|OwnerIndex=1|IndexInSheet=89|OwnerPartId=-1|LocationCount=2|X1=1580|Y1=35|X2=1580|Y2=20
|RECORD=4|OwnerIndex=1|IndexInSheet=90|OwnerPartId=-1|Location.X=1355|Location.Y=40|FontID=7|Text==CAGE_CODE
|RECORD=4|OwnerIndex=1|IndexInSheet=91|OwnerPartId=-1|Location.X=1352|Location.Y=56|FontID=5|Text=CAGE CODE
|RECORD=6|OwnerIndex=1|IndexInSheet=92|OwnerPartId=-1|LocationCount=2|X1=1350|Y1=65|X2=1350|Y2=35
|RECORD=6|OwnerIndex=1|IndexInSheet=93|OwnerPartId=-1|LineWidth=1|LocationCount=2|X1=1680|Y1=120|X2=1320|Y2=120
|RECORD=6|OwnerIndex=1|IndexInSheet=94|OwnerPartId=-1|LineWidth=1|LocationCount=2|X1=1680|Y1=160|X2=1320|Y2=160
|RECORD=4|OwnerIndex=1|IndexInSheet=95|OwnerPartId=-1|Location.X=1323|Location.Y=150|FontID=5|Text=PROJECT
|RECORD=6|OwnerIndex=1|IndexInSheet=96|OwnerPartId=-1|LocationCount=2|X1=1390|Y1=160|X2=1390|Y2=120
|RECORD=4|OwnerIndex=1|IndexInSheet=97|OwnerPartId=-1|Location.X=1325|Location.Y=130|FontID=7|Text==Project
|RECORD=4|OwnerIndex=1|IndexInSheet=98|OwnerPartId=-1|Location.X=1613|Location.Y=129|Justification=2|FontID=8|Text==Address3|IsMirrored=T
|RECORD=4|OwnerIndex=1|IndexInSheet=99|OwnerPartId=-1|Location.X=1614|Location.Y=120|Justification=2|FontID=8|Text==Address4|IsMirrored=T
|RECORD=4|OwnerIndex=1|IndexInSheet=100|OwnerPartId=-1|Location.X=1614|Location.Y=150|Justification=2|FontID=8|Text==Address1|IsMirrored=T
|RECORD=4|OwnerIndex=1|IndexInSheet=101|OwnerPartId=-1|Location.X=1614|Location.Y=144|Justification=5|FontID=8|Text==Address2|IsMirrored=T
|RECORD=6|OwnerIndex=1|IndexInSheet=102|OwnerPartId=1|LineWidth=1|LocationCount=2|X1=1320|Y1=65|X2=1320|Y2=35
|RECORD=6|OwnerIndex=1|IndexInSheet=103|OwnerPartId=1|LineWidth=1|LocationCount=2|X1=1320|Y1=35|X2=1320|Y2=20
|RECORD=6|OwnerIndex=1|IndexInSheet=104|OwnerPartId=1|LineWidth=1|LocationCount=2|X1=1320|Y1=65|X2=1320|Y2=120
|RECORD=6|OwnerIndex=1|IndexInSheet=105|OwnerPartId=1|LineWidth=1|LocationCount=2|X1=1320|Y1=120|X2=1320|Y2=160
|RECORD=6|OwnerIndex=1|IndexInSheet=106|OwnerPartId=1|LineWidth=1|LocationCount=3|X1=1320|Y1=160|X2=1180|Y2=160|X3=1180|Y3=20
|RECORD=4|OwnerIndex=1|IndexInSheet=107|OwnerPartId=1|Location.X=1212|Location.Y=145|FontID=5|Text=APPROVALS
|RECORD=4|OwnerIndex=1|IndexInSheet=108|OwnerPartId=1|Location.X=1290|Location.Y=145|FontID=5|Text=DATE
|RECORD=4|OwnerIndex=1|IndexInSheet=109|OwnerPartId=1|Location.X=1182|Location.Y=131|FontID=5|Text=ENG:
|RECORD=4|OwnerIndex=1|IndexInSheet=110|OwnerPartId=1|Location.X=1182|Location.Y=116|FontID=5|Text=DSN:
|RECORD=6|OwnerIndex=1|IndexInSheet=111|OwnerPartId=1|LocationCount=2|X1=1180|Y1=125|X2=1320|Y2=125
|RECORD=6|OwnerIndex=1|IndexInSheet=112|OwnerPartId=1|LocationCount=2|X1=1180|Y1=140|X2=1320|Y2=140
|RECORD=6|OwnerIndex=1|IndexInSheet=113|OwnerPartId=1|LocationCount=2|X1=1280|Y1=160|X2=1280|Y2=95
|RECORD=4|OwnerIndex=1|IndexInSheet=114|OwnerPartId=1|Location.X=1210|Location.Y=125|FontID=5|Text==Engineer
|RECORD=4|OwnerIndex=1|IndexInSheet=115|OwnerPartId=1|Location.X=1210|Location.Y=110|FontID=5|Text==DrawnBy
|RECORD=4|OwnerIndex=1|IndexInSheet=116|OwnerPartId=1|Location.X=1285|Location.Y=125|FontID=5|Text==ENG_APP_DATE
|RECORD=4|OwnerIndex=1|IndexInSheet=117|OwnerPartId=1|Location.X=1285|Location.Y=110|FontID=5|Text==DSN_APP_DATE
|RECORD=6|OwnerIndex=1|IndexInSheet=118|OwnerPartId=1|LineWidth=1|LocationCount=2|X1=1180|Y1=95|X2=1320|Y2=95
|RECORD=6|OwnerIndex=1|IndexInSheet=119|OwnerPartId=1|LocationCount=2|X1=1180|Y1=110|X2=1320|Y2=110
|RECORD=4|OwnerIndex=1|IndexInSheet=120|OwnerPartId=1|Location.X=1182|Location.Y=101|FontID=5|Text=CHK:
|RECORD=4|OwnerIndex=1|IndexInSheet=121|OwnerPartId=1|Location.X=1285|Location.Y=95|FontID=5|Text==CHK_APP_DATE
|RECORD=6|OwnerIndex=1|IndexInSheet=122|OwnerPartId=1|LocationCount=2|X1=1180|Y1=65|X2=1320|Y2=65
|RECORD=6|OwnerIndex=1|IndexInSheet=123|OwnerPartId=1|LocationCount=2|X1=1180|Y1=80|X2=1320|Y2=80
|RECORD=6|OwnerIndex=1|IndexInSheet=124|OwnerPartId=1|LocationCount=2|X1=1180|Y1=35|X2=1320|Y2=35
|RECORD=6|OwnerIndex=1|IndexInSheet=125|OwnerPartId=1|LocationCount=2|X1=1180|Y1=50|X2=1320|Y2=50
|RECORD=4|OwnerIndex=1|IndexInSheet=126|OwnerPartId=-1|Location.X=1204|Location.Y=82|FontID=5|Text=REFERENCE DOCUMENTS
|RECORD=4|OwnerIndex=1|IndexInSheet=127|OwnerPartId=1|Location.X=1182|Location.Y=71|FontID=5|Text=BOM:
|RECORD=4|OwnerIndex=1|IndexInSheet=128|OwnerPartId=1|Location.X=1183|Location.Y=56|FontID=5|Text=ASSY DWG:
|RECORD=4|OwnerIndex=1|IndexInSheet=129|OwnerPartId=1|Location.X=1182|Location.Y=41|FontID=5|Text=FAB DWG:
|RECORD=4|OwnerIndex=1|IndexInSheet=130|OwnerPartId=1|Location.X=1182|Location.Y=26|FontID=5|Text=PCB DWG:
|RECORD=4|OwnerIndex=1|IndexInSheet=131|OwnerPartId=-1|Location.X=1228|Location.Y=22|FontID=6|Text==PCB_DWG_NO
|RECORD=4|OwnerIndex=1|IndexInSheet=132|OwnerPartId=-1|Location.X=1228|Location.Y=37|FontID=6|Text==DOC_NO_FAB_DWG
|RECORD=4|OwnerIndex=1|IndexInSheet=133|OwnerPartId=-1|Location.X=1228|Location.Y=52|FontID=6|Text==DOC_NO_ASSY_DWG
|RECORD=4|OwnerIndex=1|IndexInSheet=134|OwnerPartId=-1|Location.X=1228|Location.Y=68|FontID=6|Text==DOC_NO_BOM
|RECORD=4|OwnerIndex=1|IndexInSheet=135|OwnerPartId=1|Location.X=1210|Location.Y=96|FontID=5|Text==CheckedBy
|RECORD=4|OwnerIndex=1|IndexInSheet=136|OwnerPartId=-1|Location.X=1591|Location.Y=104|FontID=4|Text==Item
|RECORD=6|OwnerIndex=1|IndexInSheet=137|OwnerPartId=-1|LineWidth=1|LocationCount=2|X1=1320|Y1=105|X2=1680|Y2=105
|RECORD=4|OwnerIndex=1|IndexInSheet=138|OwnerPartId=-1|Location.X=1322|Location.Y=115|Justification=3|FontID=5|Text=PROJECT REVISION:
|RECORD=4|OwnerIndex=1|IndexInSheet=139|OwnerPartId=-1|Location.X=1542|Location.Y=116|Justification=3|FontID=5|Text=DESIGN ITEM:
|RECORD=4|OwnerIndex=1|IndexInSheet=140|OwnerPartId=-1|Location.X=1432|Location.Y=116|Justification=3|FontID=5|Text=DOCUMENT REVISION:
|RECORD=6|OwnerIndex=1|IndexInSheet=141|OwnerPartId=-1|LocationCount=2|X1=1430|Y1=120|X2=1430|Y2=105
|RECORD=6|OwnerIndex=1|IndexInSheet=142|OwnerPartId=-1|LocationCount=2|X1=1541|Y1=120|X2=1541|Y2=105
|RECORD=4|OwnerIndex=1|IndexInSheet=143|OwnerPartId=-1|Location.X=1392|Location.Y=104|FontID=4|Text==VersionControl_ProjFolderRevNumber
|RECORD=4|OwnerIndex=1|IndexInSheet=144|OwnerPartId=-1|Location.X=1511|Location.Y=104|FontID=4|Text==VersionControl_RevNumber
|RECORD=6|OwnerIndex=1|IndexInSheet=145|OwnerPartId=-1|LineWidth=1|LocationCount=2|X1=1320|Y1=65|X2=1680|Y2=65
|RECORD=4|OwnerIndex=1|IndexInSheet=146|OwnerPartId=-1|Location.X=1662|Location.Y=41|FontID=4|Text==ItemRevision
|RECORD=30|OwnerIndex=1|IndexInSheet=147|OwnerPartId=-1|Location.X=1398|Location.Y=123|Corner.X=1558|Corner.X_Frac=41666|Corner.Y=158|KeepAspect=T|EmbedImage=T|FileName=Z:\Altium Project Template\Altium Logo\Altm black.jpg
|RECORD=41|IndexInSheet=1|OwnerPartId=-1|Location.X=19|Location.Y=9|Color=8388608|FontID=1|IsHidden=T|Text=sch_PageDescription|Name=sch_PageDescription
|RECORD=41|IndexInSheet=2|OwnerPartId=-1|Location.X=179|Location.Y=5|Color=8388608|FontID=1|IsHidden=T|Text=sch_PageTitle|Name=sch_PageTitle
|RECORD=41|IndexInSheet=3|OwnerPartId=-1|Location.X=179|Location.Y=5|Color=8388608|FontID=1|IsHidden=T|Text=*|Name=PageDate
|RECORD=41|IndexInSheet=4|OwnerPartId=-1|Color=8388608|FontID=1|IsHidden=T|Text=*|Name=CurrentTime
|RECORD=41|IndexInSheet=5|OwnerPartId=-1|Color=8388608|FontID=1|IsHidden=T|Text=*|Name=CurrentDate
|RECORD=41|IndexInSheet=6|OwnerPartId=-1|Color=8388608|FontID=1|IsHidden=T|Text=*|Name=Time
|RECORD=41|IndexInSheet=7|OwnerPartId=-1|Color=8388608|FontID=1|IsHidden=T|Text=*|Name=Date
|RECORD=41|IndexInSheet=8|OwnerPartId=-1|Color=8388608|FontID=1|IsHidden=T|Text=*|Name=DocumentFullPathAndName
|RECORD=41|IndexInSheet=9|OwnerPartId=-1|Color=8388608|FontID=1|IsHidden=T|Text=*|Name=DocumentName
|RECORD=41|IndexInSheet=10|OwnerPartId=-1|Color=8388608|FontID=1|IsHidden=T|Text=*|Name=ModifiedDate
|RECORD=41|IndexInSheet=11|OwnerPartId=-1|Color=8388608|FontID=1|IsHidden=T|Text=*|Name=ApprovedBy
|RECORD=41|IndexInSheet=12|OwnerPartId=-1|Color=8388608|FontID=1|IsHidden=T|Text=*|Name=CheckedBy
|RECORD=41|IndexInSheet=13|OwnerPartId=-1|Color=8388608|FontID=1|IsHidden=T|Text=*|Name=Author
|RECORD=41|IndexInSheet=14|OwnerPartId=-1|Color=8388608|FontID=1|IsHidden=T|Text=*|Name=CompanyName
|RECORD=41|IndexInSheet=15|OwnerPartId=-1|Color=8388608|FontID=1|IsHidden=T|Text=*|Name=DrawnBy
|RECORD=41|IndexInSheet=16|OwnerPartId=-1|Color=8388608|FontID=1|IsHidden=T|Text=*|Name=Engineer
|RECORD=41|IndexInSheet=17|OwnerPartId=-1|Color=8388608|FontID=1|IsHidden=T|Text=ORGANIZATION|Name=Organization
|RECORD=41|IndexInSheet=18|OwnerPartId=-1|Color=8388608|FontID=1|IsHidden=T|Text=ADDRESS 1|Name=Address1
|RECORD=41|IndexInSheet=19|OwnerPartId=-1|Color=8388608|FontID=1|IsHidden=T|Text=ADDRESS 2|Name=Address2
|RECORD=41|IndexInSheet=20|OwnerPartId=-1|Color=8388608|FontID=1|IsHidden=T|Text=ADDRESS 3|Name=Address3
|RECORD=41|IndexInSheet=21|OwnerPartId=-1|Color=8388608|FontID=1|IsHidden=T|Text=ADDRESS 4|Name=Address4
|RECORD=41|IndexInSheet=22|OwnerPartId=-1|Color=8388608|FontID=1|IsHidden=T|Text=*|Name=Title
|RECORD=41|IndexInSheet=23|OwnerPartId=-1|Color=8388608|FontID=1|IsHidden=T|Text=*|Name=DocumentNumber
|RECORD=41|IndexInSheet=24|OwnerPartId=-1|Color=8388608|FontID=1|IsHidden=T|Text=-|Name=Revision
|RECORD=41|IndexInSheet=25|OwnerPartId=-1|Color=8388608|FontID=1|IsHidden=T|Text=2|Name=SheetNumber
|RECORD=41|IndexInSheet=26|OwnerPartId=-1|Color=8388608|FontID=1|IsHidden=T|Text=3|Name=SheetTotal
|RECORD=41|IndexInSheet=27|OwnerPartId=-1|Color=8388608|FontID=1|IsHidden=T|Text=*|Name=ImagePath|ReadOnlyState=1
|RECORD=41|IndexInSheet=28|OwnerPartId=-1|Color=8388608|FontID=1|IsHidden=T|Text=*|Name=Rule|ReadOnlyState=1
|RECORD=41|IndexInSheet=29|OwnerPartId=-1|Color=8388608|FontID=1|IsHidden=T|Text=*|Name=ProjectName|ReadOnlyState=1
|RECORD=41|IndexInSheet=30|OwnerPartId=-1|Location.X=839|Location.Y=9|Color=8388608|FontID=1|IsHidden=T|Text=*|Name=Title2
|RECORD=41|IndexInSheet=31|OwnerPartId=-1|Location.Y=-10|Color=8388608|FontID=1|IsHidden=T|Text=*|Name=Project
|RECORD=41|IndexInSheet=32|OwnerPartId=-1|Location.Y=-10|Color=8388608|FontID=1|IsHidden=T|Text=--/--/--|Name=ENG_APP_DATE
|RECORD=41|IndexInSheet=33|OwnerPartId=-1|Location.Y=-10|Color=8388608|FontID=1|IsHidden=T|Text=--/--/--|Name=DSN_APP_DATE
|RECORD=41|IndexInSheet=34|OwnerPartId=-1|Location.Y=-10|Color=8388608|FontID=1|IsHidden=T|Text=--/--/--|Name=CHK_APP_DATE
|RECORD=41|IndexInSheet=35|OwnerPartId=-1|Color=8388608|FontID=1|IsHidden=T|Text=*|Name=Application_BuildNumber|ReadOnlyState=1
|RECORD=1|LibReference=1029c3af85768c4190bb7ad29bc67b5|ComponentDescription=10kO ±1% 0.063W 0402 Thick Film Chip Resistor AEC-Q200 compliant|PartCount=2|DisplayModeCount=1|IndexInSheet=36|OwnerPartId=-1|Location.X=90|Location.Y=60|Orientation=1|CurrentPartId=1|LibraryPath=*|SourceLibraryName=Altium Content Vault|TargetFileName=*|AreaColor=11599871|Color=128|PartIDLocked=T|DesignItemId=CMP-26527-000128-1|AllPinCount=2
|RECORD=2|OwnerIndex=185|OwnerPartId=1|Electrical=4|PinConglomerate=35|PinLength=20|Location.X=90|Location.Y=80|Name=1|Designator=1|PinPropagationDelay=0.000000E+000
|RECORD=2|OwnerIndex=185|OwnerPartId=1|Electrical=4|PinConglomerate=33|PinLength=20|Location.X=90|Location.Y=110|Name=2|Designator=2|PinPropagationDelay=0.000000E+000
|RECORD=13|OwnerIndex=185|IsNotAccesible=T|IndexInSheet=2|OwnerPartId=1|Location.X=90|Location.Y=80|Corner.X=85|Corner.Y=83|LineWidth=1|Color=16711680
|RECORD=13|OwnerIndex=185|IsNotAccesible=T|IndexInSheet=3|OwnerPartId=1|Location.X=85|Location.Y=83|Corner.X=95|Corner.Y=88|LineWidth=1|Color=16711680
|RECORD=13|OwnerIndex=185|IsNotAccesible=T|IndexInSheet=4|OwnerPartId=1|Location.X=95|Location.Y=88|Corner.X=85|Corner.Y=93|LineWidth=1|Color=16711680
|RECORD=13|OwnerIndex=185|IsNotAccesible=T|IndexInSheet=5|OwnerPartId=1|Location.X=85|Location.Y=93|Corner.X=95|Corner.Y=98|LineWidth=1|Color=16711680
|RECORD=13|OwnerIndex=185|IsNotAccesible=T|IndexInSheet=6|OwnerPartId=1|Location.X=95|Location.Y=98|Corner.X=85|Corner.Y=103|LineWidth=1|Color=16711680
|RECORD=13|OwnerIndex=185|IsNotAccesible=T|IndexInSheet=7|OwnerPartId=1|Location.X=85|Location.Y=103|Corner.X=95|Corner.Y=108|LineWidth=1|Color=16711680
|RECORD=13|OwnerIndex=185|IsNotAccesible=T|IndexInSheet=8|OwnerPartId=1|Location.X=95|Location.Y=108|Corner.X=90|Corner.Y=110|LineWidth=1|Color=16711680
|RECORD=13|OwnerIndex=185|IsNotAccesible=T|IndexInSheet=9|OwnerPartId=1|Location.X=90|Location.Y=80|Corner.X=90|Corner.Y=77|LineWidth=1|Color=16711680
|RECORD=13|OwnerIndex=185|IsNotAccesible=T|IndexInSheet=10|OwnerPartId=1|Location.X=90|Location.Y=110|Corner.X=90|Corner.Y=113|LineWidth=1|Color=16711680
|RECORD=41|OwnerIndex=185|IndexInSheet=11|OwnerPartId=-1|Location.X=84|Location.Y=132|Color=8388608|FontID=1|IsHidden=T|Text=0.02inch|Name=Width
|RECORD=41|OwnerIndex=185|IndexInSheet=12|OwnerPartId=-1|Location.X=84|Location.Y=132|Color=8388608|FontID=1|IsHidden=T|Text=0402|Name=Case/Package
|RECORD=41|OwnerIndex=185|IndexInSheet=13|OwnerPartId=-1|Location.X=84|Location.Y=132|Color=8388608|FontID=1|IsHidden=T|Text=100ppm/°C|Name=Temperature Coefficient
|RECORD=41|OwnerIndex=185|IndexInSheet=14|OwnerPartId=-1|Location.X=84|Location.Y=132|Color=8388608|FontID=1|IsHidden=T|Text=0.5mm|Name=Depth
|RECORD=41|OwnerIndex=185|IndexInSheet=15|OwnerPartId=-1|Location.X=84|Location.Y=132|Color=8388608|FontID=1|IsHidden=T|Text=Thick Film|Name=Resistor Type
|RECORD=41|OwnerIndex=185|IndexInSheet=16|OwnerPartId=-1|Location.X=84|Location.Y=132|Color=8388608|FontID=1|IsHidden=T|Text=RMCF|Name=Series
|RECORD=41|OwnerIndex=185|IndexInSheet=17|OwnerPartId=-1|Location.X=84|Location.Y=132|Color=8388608|FontID=1|IsHidden=T|Text=1mm|Name=Length
|RECORD=41|OwnerIndex=185|IndexInSheet=18|OwnerPartId=-1|Location.X=84|Location.Y=132|Color=8388608|FontID=1|IsHidden=T|Text=62.5mW|Name=Power Rating
|RECORD=41|OwnerIndex=185|IndexInSheet=19|OwnerPartId=-1|Location.X=84|Location.Y=132|Color=8388608|FontID=1|IsHidden=T|Text=10kR|Name=Resistance
|RECORD=41|OwnerIndex=185|IndexInSheet=20|OwnerPartId=-1|Location.X=84|Location.Y=132|Color=8388608|FontID=1|IsHidden=T|Text=Tin|Name=Contact Plating
|RECORD=41|OwnerIndex=185|IndexInSheet=21|OwnerPartId=-1|Location.X=84|Location.Y=132|Color=8388608|FontID=1|IsHidden=T|Text=1%|Name=Tolerance
|RECORD=41|OwnerIndex=185|IndexInSheet=22|OwnerPartId=-1|Location.X=84|Location.Y=132|Color=8388608|FontID=1|IsHidden=T|Text=2|Name=Number of Terminations
|RECORD=41|OwnerIndex=185|IndexInSheet=23|OwnerPartId=-1|Location.X=84|Location.Y=132|Color=8388608|FontID=1|IsHidden=T|Text=0.016inch|Name=Height
|RECORD=41|OwnerIndex=185|IndexInSheet=24|OwnerPartId=-1|Location.X=84|Location.Y=132|Color=8388608|FontID=1|IsHidden=T|Text=Not|Name=Military Standard
|RECORD=41|OwnerIndex=185|IndexInSheet=25|OwnerPartId=-1|Location.X=84|Location.Y=132|Color=8388608|FontID=1|IsHidden=T|Text=0402|Name=Case Code (Imperial)
|RECORD=41|OwnerIndex=185|IndexInSheet=26|OwnerPartId=-1|Location.X=84|Location.Y=132|Color=8388608|FontID=1|IsHidden=T|Text=63mW|Name=Max Power Dissipation
|RECORD=41|OwnerIndex=185|IndexInSheet=27|OwnerPartId=-1|Location.X=84|Location.Y=132|Color=8388608|FontID=1|IsHidden=T|Text=0402|Name=Size Code
|RECORD=41|OwnerIndex=185|IndexInSheet=28|OwnerPartId=-1|Location.X=84|Location.Y=132|Color=8388608|FontID=1|IsHidden=T|Text=Rectangular|Name=Construction
|RECORD=41|OwnerIndex=185|IndexInSheet=29|OwnerPartId=-1|Location.X=84|Location.Y=132|Color=8388608|FontID=1|IsHidden=T|Text=No|Name=Radiation Hardening
|RECORD=41|OwnerIndex=185|IndexInSheet=30|OwnerPartId=-1|Location.X=84|Location.Y=132|Color=8388608|FontID=1|IsHidden=T|Text=Yes|Name=RoHS Compliant
|RECORD=41|OwnerIndex=185|IndexInSheet=31|OwnerPartId=-1|Location.X=84|Location.Y=132|Color=8388608|FontID=1|IsHidden=T|Text=1005|Name=Case Code (Metric)
|RECORD=41|OwnerIndex=185|IndexInSheet=32|OwnerPartId=-1|Location.X=84|Location.Y=132|Color=8388608|FontID=1|IsHidden=T|Text=Tape and Reel|Name=Packaging
|RECORD=41|OwnerIndex=185|IndexInSheet=33|OwnerPartId=-1|Location.X=84|Location.Y=132|Color=8388608|FontID=1|IsHidden=T|Text=Lead Free|Name=Lead Free
|RECORD=41|OwnerIndex=185|IndexInSheet=34|OwnerPartId=-1|Location.X=84|Location.Y=132|Color=8388608|FontID=1|IsHidden=T|Text=-55°C|Name=Min Operating Temperature
|RECORD=41|OwnerIndex=185|IndexInSheet=35|OwnerPartId=-1|Location.X=84|Location.Y=132|Color=8388608|FontID=1|IsHidden=T|Text=155°C|Name=Max Operating Temperature
|RECORD=41|OwnerIndex=185|IndexInSheet=36|OwnerPartId=-1|Location.X=84|Location.Y=132|Color=8388608|FontID=1|IsHidden=T|Text=Surface Mount|Name=Mount
|RECORD=41|OwnerIndex=185|IndexInSheet=37|OwnerPartId=-1|Location.X=84|Location.Y=132|Color=8388608|FontID=1|IsHidden=T|Text=Automotive AEC-Q200|Name=Features
|RECORD=34|OwnerIndex=185|IndexInSheet=-1|OwnerPartId=-1|Location.X=96|Location.Y=104|Color=8388608|FontID=1|Text=R7|Name=Designator|ReadOnlyState=1
|RECORD=41|OwnerIndex=185|IndexInSheet=-1|OwnerPartId=1|Location.X=96|Location.Y=94|Color=8388608|FontID=1|Text=10k|Name=Comment
|RECORD=44|OwnerIndex=185
|RECORD=45|OwnerIndex=228|IndexInSheet=-1|UseComponentLibrary=T|ModelName=FP-RMCF0402-IPC_C|ModelType=PCBLIB|DatafileCount=1|ModelDatafileEntity0=FP-RMCF0402-IPC_C|ModelDatafileKind0=PCBLib|IsCurrent=T|DatalinksLocked=T|DatabaseDatalinksLocked=T
|RECORD=46|OwnerIndex=229
|RECORD=48|OwnerIndex=229
|RECORD=45|OwnerIndex=228|IndexInSheet=-1|UseComponentLibrary=T|ModelName=FP-RMCF0402-MFG|ModelType=PCBLIB|DatafileCount=1|ModelDatafileEntity0=FP-RMCF0402-MFG|ModelDatafileKind0=PCBLib|DatalinksLocked=T|DatabaseDatalinksLocked=T
|RECORD=46|OwnerIndex=232
|RECORD=48|OwnerIndex=232
|RECORD=45|OwnerIndex=228|IndexInSheet=-1|UseComponentLibrary=T|ModelName=FP-RMCF0402-IPC_A|ModelType=PCBLIB|DatafileCount=1|ModelDatafileEntity0=FP-RMCF0402-IPC_A|ModelDatafileKind0=PCBLib|DatalinksLocked=T|DatabaseDatalinksLocked=T
|RECORD=46|OwnerIndex=235
|RECORD=48|OwnerIndex=235
|RECORD=45|OwnerIndex=228|IndexInSheet=-1|UseComponentLibrary=T|ModelName=FP-RMCF0402-IPC_B|ModelType=PCBLIB|DatafileCount=1|ModelDatafileEntity0=FP-RMCF0402-IPC_B|ModelDatafileKind0=PCBLib|DatalinksLocked=T|DatabaseDatalinksLocked=T
|RECORD=46|OwnerIndex=238
|RECORD=48|OwnerIndex=238
|RECORD=1|LibReference=NRPN042MAMS-RC|ComponentDescription=Dual Row 8 Position 2 mm Pitch Surface Mount Header|PartCount=2|DisplayModeCount=1|IndexInSheet=37|OwnerPartId=-1|Location.X=110|Location.Y=610|CurrentPartId=1|LibraryPath=*|SourceLibraryName=GNSS_Receiver_Library.IntLib|TargetFileName=*|AreaColor=11599871|Color=128|PartIDLocked=T|DesignItemId=NRPN042MAMS-RC|AllPinCount=8
|RECORD=41|OwnerIndex=241|OwnerPartId=-1|Location.X=88|Location.Y=625|Color=8388608|FontID=1|IsHidden=T|Text=Digi-Key|Name=Supplier 1|ReadOnlyState=3
|RECORD=41|OwnerIndex=241|IndexInSheet=1|OwnerPartId=-1|Location.X=88|Location.Y=635|Color=8388608|FontID=1|IsHidden=T|Text=Sullins|Name=Manufacturer
|RECORD=41|OwnerIndex=241|IndexInSheet=2|OwnerPartId=-1|Location.X=88|Location.Y=635|Color=8388608|FontID=1|IsHidden=T|Text=NRPN042MAMS-RC|Name=Manufacturer Part Number
|RECORD=41|OwnerIndex=241|IndexInSheet=3|OwnerPartId=-1|Location.X=88|Location.Y=635|Color=8388608|FontID=1|IsHidden=T|Text=Yes|Name=RoHS
|RECORD=41|OwnerIndex=241|IndexInSheet=4|OwnerPartId=-1|Location.X=88|Location.Y=635|Color=8388608|FontID=1|IsHidden=T|Text=Connectors|Name=Category
|RECORD=41|OwnerIndex=241|IndexInSheet=5|OwnerPartId=-1|Location.X=88|Location.Y=635|Color=8388608|FontID=1|IsHidden=T|Text=10801|Name=Stock 1|ReadOnlyState=3
|RECORD=41|OwnerIndex=241|IndexInSheet=6|OwnerPartId=-1|Location.X=88|Location.Y=635|Color=8388608|FontID=1|IsHidden=T|Text=1=0.76000, 76=0.60237, 152=0.57618, 456=0.47143, 988=0.41904, 4940=0.37830 (USD)|Name=Pricing 1|ReadOnlyState=3
|RECORD=41|OwnerIndex=241|IndexInSheet=7|OwnerPartId=-1|Location.X=88|Location.Y=635|Color=8388608|FontID=1|IsHidden=T|Text=Surface Mount|Name=Mount
|RECORD=41|OwnerIndex=241|IndexInSheet=8|OwnerPartId=-1|Location.X=88|Location.Y=635|Color=8388608|FontID=1|IsHidden=T|Text=Black|Name=Color
|RECORD=41|OwnerIndex=241|IndexInSheet=9|OwnerPartId=-1|Location.X=88|Location.Y=635|Color=8388608|FontID=1|IsHidden=T|Text=Gold|Name=Contact Plating
|RECORD=41|OwnerIndex=241|IndexInSheet=10|OwnerPartId=-1|Location.X=88|Location.Y=635|Color=8388608|FontID=1|IsHidden=T|Text=Brass|Name=Contact Material
|RECORD=41|OwnerIndex=241|IndexInSheet=11|OwnerPartId=-1|Location.X=88|Location.Y=635|Color=8388608|FontID=1|IsHidden=T|Text=Nylon|Name=Housing Material
|RECORD=41|OwnerIndex=241|IndexInSheet=12|OwnerPartId=-1|Location.X=88|Location.Y=635|Color=8388608|FontID=1|IsHidden=T|Text=1000|Name=Package Quantity
|RECORD=41|OwnerIndex=241|IndexInSheet=13|OwnerPartId=-1|Location.X=88|Location.Y=635|Color=8388608|FontID=1|IsHidden=T|Text=2|Name=Number of Rows
|RECORD=41|OwnerIndex=241|IndexInSheet=14|OwnerPartId=-1|Location.X=88|Location.Y=635|Color=8388608|FontID=1|IsHidden=T|Text=Bulk|Name=Packaging
|RECORD=41|OwnerIndex=241|IndexInSheet=15|OwnerPartId=-1|Location.X=88|Location.Y=635|Color=8388608|FontID=1|IsHidden=T|Text=8|Name=Number of Positions
|RECORD=41|OwnerIndex=241|IndexInSheet=16|OwnerPartId=-1|Location.X=88|Location.Y=635|Color=8388608|FontID=1|IsHidden=T|Text=Solder|Name=Termination
|RECORD=41|OwnerIndex=241|IndexInSheet=17|OwnerPartId=-1|Location.X=88|Location.Y=635|Color=8388608|FontID=1|IsHidden=T|Text=Male Pin|Name=Connector Type
|RECORD=41|OwnerIndex=241|IndexInSheet=18|OwnerPartId=-1|Location.X=88|Location.Y=635|Color=8388608|FontID=1|IsHidden=T|Text=Male Pin|Name=Contact Type
|RECORD=41|OwnerIndex=241|IndexInSheet=19|OwnerPartId=-1|Location.X=88|Location.Y=635|Color=8388608|FontID=1|IsHidden=T|Text=8mm|Name=Length
|RECORD=41|OwnerIndex=241|IndexInSheet=20|OwnerPartId=-1|Location.X=88|Location.Y=635|Color=8388608|FontID=1|IsHidden=T|Text=4mm|Name=Width
|RECORD=41|OwnerIndex=241|IndexInSheet=21|OwnerPartId=-1|Location.X=88|Location.Y=635|Color=8388608|FontID=1|IsHidden=T|Text=1.5mm|Name=Height
|RECORD=41|OwnerIndex=241|IndexInSheet=22|OwnerPartId=-1|Location.X=88|Location.Y=635|Color=8388608|FontID=1|IsHidden=T|Text=0.079inch|Name=Pitch
|RECORD=41|OwnerIndex=241|IndexInSheet=23|OwnerPartId=-1|Location.X=88|Location.Y=635|Color=8388608|FontID=1|IsHidden=T|Text=0.079inch|Name=Row Spacing
|RECORD=41|OwnerIndex=241|IndexInSheet=24|OwnerPartId=-1|Location.X=88|Location.Y=635|Color=8388608|FontID=1|IsHidden=T|Text=0.141inch|Name=Contact Mating Length
|RECORD=41|OwnerIndex=241|IndexInSheet=25|OwnerPartId=-1|Location.X=88|Location.Y=635|Color=8388608|FontID=1|IsHidden=T|Text=Lead Free|Name=Lead Free
|RECORD=41|OwnerIndex=241|IndexInSheet=26|OwnerPartId=-1|Location.X=88|Location.Y=635|Color=8388608|FontID=1|IsHidden=T|Text=Yes|Name=RoHS Compliant
|RECORD=41|OwnerIndex=241|IndexInSheet=27|OwnerPartId=-1|Location.X=88|Location.Y=635|Color=8388608|FontID=2|IsHidden=T|Text=https://datasheet.ciiva.com/711/nrpnxx2mamx-rc-10495-d-711179.pdf?src-supplier=Digi-Key|Name=ComponentLink1URL
|RECORD=41|OwnerIndex=241|IndexInSheet=28|OwnerPartId=-1|Location.X=88|Location.Y=635|Color=8388608|FontID=2|IsHidden=T|Text=https://datasheet.ciiva.com/711/nrpnxx2mamx-rc-10495-d-711179.pdf?src-supplier=Digi-Key|Name=ComponentLink1Description
|RECORD=14|OwnerIndex=241|IsNotAccesible=T|IndexInSheet=29|OwnerPartId=1|Location.X=110|Location.Y=560|Corner.X=140|Corner.Y=610|Color=128|AreaColor=11599871|IsSolid=T
|RECORD=2|OwnerIndex=241|OwnerPartId=1|FormalType=1|Electrical=4|PinConglomerate=42|PinLength=20|Location.X=110|Location.Y=600|Name=1|Designator=1|SwapIDPart=Ž&Ž||PinPropagationDelay=0.000000E+000
|RECORD=2|OwnerIndex=241|OwnerPartId=1|FormalType=1|Electrical=4|PinConglomerate=40|PinLength=20|Location.X=140|Location.Y=600|Name=2|Designator=2|SwapIDPart=Ž&Ž||PinPropagationDelay=0.000000E+000
|RECORD=2|OwnerIndex=241|OwnerPartId=1|FormalType=1|Electrical=4|PinConglomerate=42|PinLength=20|Location.X=110|Location.Y=590|Name=3|Designator=3|SwapIDPart=Ž&Ž||PinPropagationDelay=0.000000E+000
|RECORD=2|OwnerIndex=241|OwnerPartId=1|FormalType=1|Electrical=4|PinConglomerate=40|PinLength=20|Location.X=140|Location.Y=590|Name=4|Designator=4|SwapIDPart=Ž&Ž||PinPropagationDelay=0.000000E+000
|RECORD=2|OwnerIndex=241|OwnerPartId=1|FormalType=1|Electrical=4|PinConglomerate=42|PinLength=20|Location.X=110|Location.Y=580|Name=5|Designator=5|SwapIDPart=Ž&Ž||PinPropagationDelay=0.000000E+000
|RECORD=2|OwnerIndex=241|OwnerPartId=1|FormalType=1|Electrical=4|PinConglomerate=40|PinLength=20|Location.X=140|Location.Y=580|Name=6|Designator=6|SwapIDPart=Ž&Ž||PinPropagationDelay=0.000000E+000
|RECORD=2|OwnerIndex=241|OwnerPartId=1|FormalType=1|Electrical=4|PinConglomerate=42|PinLength=20|Location.X=110|Location.Y=570|Name=7|Designator=7|SwapIDPart=Ž&Ž||PinPropagationDelay=0.000000E+000
|RECORD=2|OwnerIndex=241|OwnerPartId=1|FormalType=1|Electrical=4|PinConglomerate=40|PinLength=20|Location.X=140|Location.Y=570|Name=8|Designator=8|SwapIDPart=Ž&Ž||PinPropagationDelay=0.000000E+000
|RECORD=41|OwnerIndex=241|IndexInSheet=38|OwnerPartId=-1|Location.X=110|Location.Y=540|Color=8388608|FontID=1|IsHidden=T|Text=S6009-04-ND|Name=Supplier Part Number 1|ReadOnlyState=3
|RECORD=34|OwnerIndex=241|IndexInSheet=-1|OwnerPartId=-1|Location.X=110|Location.Y=610|Color=8388608|FontID=1|Text=J1|Name=Designator|ReadOnlyState=1
|RECORD=41|OwnerIndex=241|IndexInSheet=-1|OwnerPartId=-1|Location.X=110|Location.Y=550|Color=8388608|FontID=1|Text=NRPN042MAMS-RC|Name=Comment
|RECORD=44|OwnerIndex=241
|RECORD=45|OwnerIndex=291|IndexInSheet=-1|UseComponentLibrary=T|ModelName=NRPN042MAMS-RC|ModelType=PCBLIB|DatafileCount=1|ModelDatafileEntity0=NRPN042MAMS-RC|ModelDatafileKind0=PCBLib|IsCurrent=T|DatalinksLocked=T|DatabaseDatalinksLocked=T|IntegratedModel=T|DatabaseModel=T
|RECORD=46|OwnerIndex=292
|RECORD=48|OwnerIndex=292
|RECORD=17|IndexInSheet=38|OwnerPartId=-1|Style=2|ShowNetName=T|Location.X=60|Location.Y=600|Orientation=1|Color=128|FontID=1|Text=VCC_ANT
|RECORD=17|IndexInSheet=39|OwnerPartId=-1|Style=2|ShowNetName=T|Location.X=190|Location.Y=600|Orientation=1|Color=128|FontID=1|Text=VCC
|RECORD=25|IndexInSheet=40|OwnerPartId=-1|Location.X=60|Location.Y=590|Color=128|FontID=1|Text=TXD_OUT
|RECORD=25|IndexInSheet=41|OwnerPartId=-1|Location.X=190|Location.Y=590|Justification=2|Color=128|FontID=1|Text=RST
|RECORD=25|IndexInSheet=42|OwnerPartId=-1|Location.X=60|Location.Y=580|Color=128|FontID=1|Text=RXD_IN
|RECORD=25|IndexInSheet=43|OwnerPartId=-1|Location.X=190|Location.Y=580|Justification=2|Color=128|FontID=1|Text=TP1
|RECORD=25|IndexInSheet=44|OwnerPartId=-1|Location.X=60|Location.Y=570|Color=128|FontID=1|Text=TP2
|RECORD=17|IndexInSheet=45|OwnerPartId=-1|Style=4|ShowNetName=F|Location.X=200|Location.Y=570|Orientation=3|Color=128|FontID=1|Text=GND
|RECORD=1|LibReference=TI-SN74XXX3G0X-XX-8|ComponentDescription=Triple Buffer/Driver With Open-Drain Output, DCU0008A, LARGE T&R|PartCount=5|DisplayModeCount=1|IndexInSheet=46|OwnerPartId=-1|Location.X=110|Location.Y=490|CurrentPartId=1|LibraryPath=*|SourceLibraryName=Altium Content Vault|TargetFileName=*|AreaColor=11599871|Color=128|PartIDLocked=T|DesignItemId=CMP-0859-00615-3|AllPinCount=8
|RECORD=2|OwnerIndex=303|OwnerPartId=3|FormalType=1|Electrical=3|PinConglomerate=48|PinLength=20|Location.X=140|Location.Y=470|Name=3Y|Designator=2|SwapIDPart=Ž&Ž2|PinPropagationDelay=0.000000E+000
|RECORD=2|OwnerIndex=303|OwnerPartId=3|FormalType=1|PinConglomerate=50|PinLength=20|Location.X=110|Location.Y=470|Name=3A|Designator=6|SwapIDPart=Ž&Ž2|PinPropagationDelay=0.000000E+000
|RECORD=13|OwnerIndex=303|IsNotAccesible=T|IndexInSheet=2|OwnerPartId=3|Location.X=110|Location.Y=485|Corner.X=140|Corner.Y=470|LineWidth=1|Color=16711680
|RECORD=13|OwnerIndex=303|IsNotAccesible=T|IndexInSheet=3|OwnerPartId=3|Location.X=110|Location.Y=455|Corner.X=140|Corner.Y=470|LineWidth=1|Color=16711680
|RECORD=13|OwnerIndex=303|IsNotAccesible=T|IndexInSheet=4|OwnerPartId=3|Location.X=110|Location.Y=455|Corner.X=110|Corner.Y=485|LineWidth=1|Color=16711680
|RECORD=2|OwnerIndex=303|OwnerPartId=2|FormalType=1|Electrical=3|PinConglomerate=48|PinLength=20|Location.X=140|Location.Y=470|Name=2Y|Designator=5|SwapIDPart=Ž&Ž2|PinPropagationDelay=0.000000E+000
|RECORD=2|OwnerIndex=303|OwnerPartId=2|FormalType=1|PinConglomerate=50|PinLength=20|Location.X=110|Location.Y=470|Name=2A|Designator=3|SwapIDPart=Ž&Ž2|PinPropagationDelay=0.000000E+000
|RECORD=13|OwnerIndex=303|IsNotAccesible=T|IndexInSheet=7|OwnerPartId=2|Location.X=110|Location.Y=485|Corner.X=140|Corner.Y=470|LineWidth=1|Color=16711680
|RECORD=13|OwnerIndex=303|IsNotAccesible=T|IndexInSheet=8|OwnerPartId=2|Location.X=110|Location.Y=455|Corner.X=140|Corner.Y=470|LineWidth=1|Color=16711680
|RECORD=13|OwnerIndex=303|IsNotAccesible=T|IndexInSheet=9|OwnerPartId=2|Location.X=110|Location.Y=455|Corner.X=110|Corner.Y=485|LineWidth=1|Color=16711680
|RECORD=14|OwnerIndex=303|IsNotAccesible=T|IndexInSheet=10|OwnerPartId=4|Location.X=110|Location.Y=470|Corner.X=170|Corner.Y=490|Color=128|AreaColor=11599871|IsSolid=T
|RECORD=2|OwnerIndex=303|OwnerPartId=4|FormalType=1|Electrical=7|PinConglomerate=56|PinLength=20|Location.X=170|Location.Y=480|Name=GND|Designator=4|PinPropagationDelay=0.000000E+000
|RECORD=2|OwnerIndex=303|OwnerPartId=4|FormalType=1|Electrical=7|PinConglomerate=58|PinLength=20|Location.X=110|Location.Y=480|Name=VCC|Designator=8|PinPropagationDelay=0.000000E+000
|RECORD=2|OwnerIndex=303|OwnerPartId=1|FormalType=1|Electrical=3|PinConglomerate=48|PinLength=20|Location.X=140|Location.Y=470|Name=1Y|Designator=7|SwapIDPart=Ž&Ž2|PinPropagationDelay=0.000000E+000
|RECORD=2|OwnerIndex=303|OwnerPartId=1|FormalType=1|PinConglomerate=50|PinLength=20|Location.X=110|Location.Y=470|Name=1A|Designator=1|SwapIDPart=Ž&Ž2|PinPropagationDelay=0.000000E+000
|RECORD=13|OwnerIndex=303|IsNotAccesible=T|IndexInSheet=15|OwnerPartId=1|Location.X=110|Location.Y=485|Corner.X=140|Corner.Y=470|LineWidth=1|Color=16711680
|RECORD=13|OwnerIndex=303|IsNotAccesible=T|IndexInSheet=16|OwnerPartId=1|Location.X=110|Location.Y=455|Corner.X=140|Corner.Y=470|LineWidth=1|Color=16711680
|RECORD=13|OwnerIndex=303|IsNotAccesible=T|IndexInSheet=17|OwnerPartId=1|Location.X=110|Location.Y=455|Corner.X=110|Corner.Y=485|LineWidth=1|Color=16711680
|RECORD=41|OwnerIndex=303|IndexInSheet=18|OwnerPartId=-1|Location.X=88|Location.Y=505|Color=8388608|FontID=1|IsHidden=T|Text=SN74LVC3G07|Name=Generic Part Number
|RECORD=41|OwnerIndex=303|IndexInSheet=19|OwnerPartId=-1|Location.X=88|Location.Y=505|Color=8388608|FontID=1|IsHidden=T|Text=5.5|Name=VCC(Max)(V)
|RECORD=41|OwnerIndex=303|IndexInSheet=20|OwnerPartId=-1|Location.X=88|Location.Y=505|Color=8388608|FontID=1|IsHidden=T|Text=Non-Inverting Buffer/Driver|Name=Sub-Family
|RECORD=41|OwnerIndex=303|IndexInSheet=21|OwnerPartId=-1|Location.X=88|Location.Y=505|Color=8388608|FontID=1|IsHidden=T|Text=True|Name=Logic
|RECORD=41|OwnerIndex=303|IndexInSheet=22|OwnerPartId=-1|Location.X=88|Location.Y=505|Color=8388608|FontID=1|IsHidden=T|Text=DCU0008A|Name=PackageReference
|RECORD=41|OwnerIndex=303|IndexInSheet=23|OwnerPartId=-1|Location.X=88|Location.Y=505|Color=8388608|FontID=1|IsHidden=T|Text=8.3,4.8,4.2,3.4|Name=tpd @ Nom Voltage(Max)(ns)
|RECORD=41|OwnerIndex=303|IndexInSheet=24|OwnerPartId=-1|Location.X=88|Location.Y=505|Color=8388608|FontID=1|IsHidden=T|Text=CMOS|Name=Output Type
|RECORD=41|OwnerIndex=303|IndexInSheet=25|OwnerPartId=-1|Location.X=88|Location.Y=505|Color=8388608|FontID=1|IsHidden=T|Text=150|Name=F @ Nom Voltage(Max)(Mhz)
|RECORD=41|OwnerIndex=303|IndexInSheet=26|OwnerPartId=-1|Location.X=88|Location.Y=505|Color=8388608|FontID=1|IsHidden=T|Text=LVC|Name=Technology Family
|RECORD=41|OwnerIndex=303|IndexInSheet=27|OwnerPartId=-1|Location.X=88|Location.Y=505|Color=8388608|FontID=1|IsHidden=T|Text=0.01|Name=ICC @ Nom Voltage(Max)(mA)
|RECORD=41|OwnerIndex=303|IndexInSheet=28|OwnerPartId=-1|Location.X=88|Location.Y=505|Color=8388608|FontID=1|IsHidden=T|Text=1.8,2.5,3.3,5|Name=Voltage(Nom)(V)
|RECORD=41|OwnerIndex=303|IndexInSheet=29|OwnerPartId=-1|Location.X=88|Location.Y=505|Color=8388608|FontID=1|IsHidden=T|Text=No|Name=Schmitt Trigger
|RECORD=41|OwnerIndex=303|IndexInSheet=30|OwnerPartId=-1|Location.X=88|Location.Y=505|Color=8388608|FontID=1|IsHidden=T|Text=Texas Instruments|Name=Manufacturer
|RECORD=41|OwnerIndex=303|IndexInSheet=31|OwnerPartId=-1|Location.X=88|Location.Y=505|Color=8388608|FontID=1|IsHidden=T|Text=1.65|Name=VCC(Min)(V)
|RECORD=41|OwnerIndex=303|IndexInSheet=32|OwnerPartId=-1|Location.X=88|Location.Y=505|Color=8388608|FontID=1|IsHidden=T|Text=No|Name=3-State Output
|RECORD=41|OwnerIndex=303|IndexInSheet=33|OwnerPartId=-1|Location.X=88|Location.Y=505|Color=8388608|FontID=1|IsHidden=T|Text=3|Name=Bits(#)
|RECORD=41|OwnerIndex=303|IndexInSheet=34|OwnerPartId=-1|Location.X=88|Location.Y=505|Color=8388608|FontID=1|IsHidden=T|Text=SCES365K|Name=DatasheetVersion
|RECORD=41|OwnerIndex=303|IndexInSheet=35|OwnerPartId=-1|Location.X=88|Location.Y=505|Color=8388608|FontID=1|IsHidden=T|Text=CMOS/TTL|Name=Input Type
|RECORD=41|OwnerIndex=303|IndexInSheet=36|OwnerPartId=-1|Location.X=88|Location.Y=505|Color=8388608|FontID=1|IsHidden=T|Text=Catalog|Name=Rating
|RECORD=41|OwnerIndex=303|IndexInSheet=37|OwnerPartId=-1|Location.X=88|Location.Y=505|Color=8388608|FontID=1|IsHidden=T|Text=32/-32|Name=Output Drive (IOL/IOH)(Max)(mA)
|RECORD=41|OwnerIndex=303|IndexInSheet=38|OwnerPartId=-1|Location.X=88|Location.Y=505|Color=8388608|FontID=1|IsHidden=T|Text=-40 to 125,-40 to 85|Name=Operating Temperature Range(C)
|RECORD=34|OwnerIndex=303|IndexInSheet=-1|OwnerPartId=-1|Location.X=109|Location.Y=486|Color=8388608|FontID=1|Text=U2|Name=Designator|ReadOnlyState=1
|RECORD=41|OwnerIndex=303|IndexInSheet=-1|OwnerPartId=-1|Location.X=109|Location.Y=444|Color=8388608|FontID=1|Text=SN74LVC3G07DCUR|Name=Comment
|RECORD=44|OwnerIndex=303
|RECORD=45|OwnerIndex=353|IndexInSheet=-1|Description=SOP, 8-Leads, Body 2.4x2.1mm, Pitch 0.5mm, IPC Medium Density|UseComponentLibrary=T|ModelName=DCU0008A_N|ModelType=PCBLIB|DatafileCount=1|ModelDatafileEntity0=DCU0008A_N|ModelDatafileKind0=PCBLib|IsCurrent=T|DatalinksLocked=T|DatabaseDatalinksLocked=T
|RECORD=46|OwnerIndex=354
|RECORD=48|OwnerIndex=354
|RECORD=41|OwnerIndex=356|IndexInSheet=-1|OwnerPartId=-1|Color=8388608|FontID=1|IsHidden=T|Text=2D|Name=Available Preview Images
|RECORD=45|OwnerIndex=353|IndexInSheet=-1|Description=SOP, 8-Leads, Body 2.4x2.1mm, Pitch 0.5mm, IPC Low Density|UseComponentLibrary=T|ModelName=DCU0008A_M|ModelType=PCBLIB|DatafileCount=1|ModelDatafileEntity0=DCU0008A_M|ModelDatafileKind0=PCBLib|DatalinksLocked=T|DatabaseDatalinksLocked=T
|RECORD=46|OwnerIndex=358
|RECORD=48|OwnerIndex=358
|RECORD=41|OwnerIndex=360|IndexInSheet=-1|OwnerPartId=-1|Color=8388608|FontID=1|IsHidden=T|Text=2D|Name=Available Preview Images
|RECORD=45|OwnerIndex=353|IndexInSheet=-1|Description=SOP, 8-Leads, Body 2.4x2.1mm, Pitch 0.5mm, IPC High Density|UseComponentLibrary=T|ModelName=DCU0008A_L|ModelType=PCBLIB|DatafileCount=1|ModelDatafileEntity0=DCU0008A_L|ModelDatafileKind0=PCBLib|DatalinksLocked=T|DatabaseDatalinksLocked=T
|RECORD=46|OwnerIndex=362
|RECORD=48|OwnerIndex=362
|RECORD=41|OwnerIndex=364|IndexInSheet=-1|OwnerPartId=-1|Color=8388608|FontID=1|IsHidden=T|Text=2D|Name=Available Preview Images
|RECORD=1|LibReference=TI-SN74XXX3G0X-XX-8|ComponentDescription=Triple Buffer/Driver With Open-Drain Output, DCU0008A, LARGE T&R|PartCount=5|DisplayModeCount=1|IndexInSheet=47|OwnerPartId=-1|Location.X=110|Location.Y=420|CurrentPartId=2|LibraryPath=*|SourceLibraryName=Altium Content Vault|TargetFileName=*|AreaColor=11599871|Color=128|PartIDLocked=F|DesignItemId=CMP-0859-00615-3|AllPinCount=8
|RECORD=2|OwnerIndex=366|OwnerPartId=3|FormalType=1|Electrical=3|PinConglomerate=48|PinLength=20|Location.X=140|Location.Y=400|Name=3Y|Designator=2|SwapIDPart=Ž&Ž2|PinPropagationDelay=0.000000E+000
|RECORD=2|OwnerIndex=366|OwnerPartId=3|FormalType=1|PinConglomerate=50|PinLength=20|Location.X=110|Location.Y=400|Name=3A|Designator=6|SwapIDPart=Ž&Ž2|PinPropagationDelay=0.000000E+000
|RECORD=13|OwnerIndex=366|IsNotAccesible=T|IndexInSheet=2|OwnerPartId=3|Location.X=110|Location.Y=415|Corner.X=140|Corner.Y=400|LineWidth=1|Color=16711680
|RECORD=13|OwnerIndex=366|IsNotAccesible=T|IndexInSheet=3|OwnerPartId=3|Location.X=110|Location.Y=385|Corner.X=140|Corner.Y=400|LineWidth=1|Color=16711680
|RECORD=13|OwnerIndex=366|IsNotAccesible=T|IndexInSheet=4|OwnerPartId=3|Location.X=110|Location.Y=385|Corner.X=110|Corner.Y=415|LineWidth=1|Color=16711680
|RECORD=2|OwnerIndex=366|OwnerPartId=2|FormalType=1|Electrical=3|PinConglomerate=48|PinLength=20|Location.X=140|Location.Y=400|Name=2Y|Designator=5|SwapIDPart=Ž&Ž2|PinPropagationDelay=0.000000E+000
|RECORD=2|OwnerIndex=366|OwnerPartId=2|FormalType=1|PinConglomerate=50|PinLength=20|Location.X=110|Location.Y=400|Name=2A|Designator=3|SwapIDPart=Ž&Ž2|PinPropagationDelay=0.000000E+000
|RECORD=13|OwnerIndex=366|IsNotAccesible=T|IndexInSheet=7|OwnerPartId=2|Location.X=110|Location.Y=415|Corner.X=140|Corner.Y=400|LineWidth=1|Color=16711680
|RECORD=13|OwnerIndex=366|IsNotAccesible=T|IndexInSheet=8|OwnerPartId=2|Location.X=110|Location.Y=385|Corner.X=140|Corner.Y=400|LineWidth=1|Color=16711680
|RECORD=13|OwnerIndex=366|IsNotAccesible=T|IndexInSheet=9|OwnerPartId=2|Location.X=110|Location.Y=385|Corner.X=110|Corner.Y=415|LineWidth=1|Color=16711680
|RECORD=14|OwnerIndex=366|IsNotAccesible=T|IndexInSheet=10|OwnerPartId=4|Location.X=110|Location.Y=400|Corner.X=170|Corner.Y=420|Color=128|AreaColor=11599871|IsSolid=T
|RECORD=2|OwnerIndex=366|OwnerPartId=4|FormalType=1|Electrical=7|PinConglomerate=56|PinLength=20|Location.X=170|Location.Y=410|Name=GND|Designator=4|PinPropagationDelay=0.000000E+000
|RECORD=2|OwnerIndex=366|OwnerPartId=4|FormalType=1|Electrical=7|PinConglomerate=58|PinLength=20|Location.X=110|Location.Y=410|Name=VCC|Designator=8|PinPropagationDelay=0.000000E+000
|RECORD=2|OwnerIndex=366|OwnerPartId=1|FormalType=1|Electrical=3|PinConglomerate=48|PinLength=20|Location.X=140|Location.Y=400|Name=1Y|Designator=7|SwapIDPart=Ž&Ž2|PinPropagationDelay=0.000000E+000
|RECORD=2|OwnerIndex=366|OwnerPartId=1|FormalType=1|PinConglomerate=50|PinLength=20|Location.X=110|Location.Y=400|Name=1A|Designator=1|SwapIDPart=Ž&Ž2|PinPropagationDelay=0.000000E+000
|RECORD=13|OwnerIndex=366|IsNotAccesible=T|IndexInSheet=15|OwnerPartId=1|Location.X=110|Location.Y=415|Corner.X=140|Corner.Y=400|LineWidth=1|Color=16711680
|RECORD=13|OwnerIndex=366|IsNotAccesible=T|IndexInSheet=16|OwnerPartId=1|Location.X=110|Location.Y=385|Corner.X=140|Corner.Y=400|LineWidth=1|Color=16711680
|RECORD=13|OwnerIndex=366|IsNotAccesible=T|IndexInSheet=17|OwnerPartId=1|Location.X=110|Location.Y=385|Corner.X=110|Corner.Y=415|LineWidth=1|Color=16711680
|RECORD=41|OwnerIndex=366|IndexInSheet=18|OwnerPartId=-1|Location.X=88|Location.Y=435|Color=8388608|FontID=1|IsHidden=T|Text=SN74LVC3G07|Name=Generic Part Number
|RECORD=41|OwnerIndex=366|IndexInSheet=19|OwnerPartId=-1|Location.X=88|Location.Y=435|Color=8388608|FontID=1|IsHidden=T|Text=5.5|Name=VCC(Max)(V)
|RECORD=41|OwnerIndex=366|IndexInSheet=20|OwnerPartId=-1|Location.X=88|Location.Y=435|Color=8388608|FontID=1|IsHidden=T|Text=Non-Inverting Buffer/Driver|Name=Sub-Family
|RECORD=41|OwnerIndex=366|IndexInSheet=21|OwnerPartId=-1|Location.X=88|Location.Y=435|Color=8388608|FontID=1|IsHidden=T|Text=True|Name=Logic
|RECORD=41|OwnerIndex=366|IndexInSheet=22|OwnerPartId=-1|Location.X=88|Location.Y=435|Color=8388608|FontID=1|IsHidden=T|Text=DCU0008A|Name=PackageReference
|RECORD=41|OwnerIndex=366|IndexInSheet=23|OwnerPartId=-1|Location.X=88|Location.Y=435|Color=8388608|FontID=1|IsHidden=T|Text=8.3,4.8,4.2,3.4|Name=tpd @ Nom Voltage(Max)(ns)
|RECORD=41|OwnerIndex=366|IndexInSheet=24|OwnerPartId=-1|Location.X=88|Location.Y=435|Color=8388608|FontID=1|IsHidden=T|Text=CMOS|Name=Output Type
|RECORD=41|OwnerIndex=366|IndexInSheet=25|OwnerPartId=-1|Location.X=88|Location.Y=435|Color=8388608|FontID=1|IsHidden=T|Text=150|Name=F @ Nom Voltage(Max)(Mhz)
|RECORD=41|OwnerIndex=366|IndexInSheet=26|OwnerPartId=-1|Location.X=88|Location.Y=435|Color=8388608|FontID=1|IsHidden=T|Text=LVC|Name=Technology Family
|RECORD=41|OwnerIndex=366|IndexInSheet=27|OwnerPartId=-1|Location.X=88|Location.Y=435|Color=8388608|FontID=1|IsHidden=T|Text=0.01|Name=ICC @ Nom Voltage(Max)(mA)
|RECORD=41|OwnerIndex=366|IndexInSheet=28|OwnerPartId=-1|Location.X=88|Location.Y=435|Color=8388608|FontID=1|IsHidden=T|Text=1.8,2.5,3.3,5|Name=Voltage(Nom)(V)
|RECORD=41|OwnerIndex=366|IndexInSheet=29|OwnerPartId=-1|Location.X=88|Location.Y=435|Color=8388608|FontID=1|IsHidden=T|Text=No|Name=Schmitt Trigger
|RECORD=41|OwnerIndex=366|IndexInSheet=30|OwnerPartId=-1|Location.X=88|Location.Y=435|Color=8388608|FontID=1|IsHidden=T|Text=Texas Instruments|Name=Manufacturer
|RECORD=41|OwnerIndex=366|IndexInSheet=31|OwnerPartId=-1|Location.X=88|Location.Y=435|Color=8388608|FontID=1|IsHidden=T|Text=1.65|Name=VCC(Min)(V)
|RECORD=41|OwnerIndex=366|IndexInSheet=32|OwnerPartId=-1|Location.X=88|Location.Y=435|Color=8388608|FontID=1|IsHidden=T|Text=No|Name=3-State Output
|RECORD=41|OwnerIndex=366|IndexInSheet=33|OwnerPartId=-1|Location.X=88|Location.Y=435|Color=8388608|FontID=1|IsHidden=T|Text=3|Name=Bits(#)
|RECORD=41|OwnerIndex=366|IndexInSheet=34|OwnerPartId=-1|Location.X=88|Location.Y=435|Color=8388608|FontID=1|IsHidden=T|Text=SCES365K|Name=DatasheetVersion
|RECORD=41|OwnerIndex=366|IndexInSheet=35|OwnerPartId=-1|Location.X=88|Location.Y=435|Color=8388608|FontID=1|IsHidden=T|Text=CMOS/TTL|Name=Input Type
|RECORD=41|OwnerIndex=366|IndexInSheet=36|OwnerPartId=-1|Location.X=88|Location.Y=435|Color=8388608|FontID=1|IsHidden=T|Text=Catalog|Name=Rating
|RECORD=41|OwnerIndex=366|IndexInSheet=37|OwnerPartId=-1|Location.X=88|Location.Y=435|Color=8388608|FontID=1|IsHidden=T|Text=32/-32|Name=Output Drive (IOL/IOH)(Max)(mA)
|RECORD=41|OwnerIndex=366|IndexInSheet=38|OwnerPartId=-1|Location.X=88|Location.Y=435|Color=8388608|FontID=1|IsHidden=T|Text=-40 to 125,-40 to 85|Name=Operating Temperature Range(C)
|RECORD=34|OwnerIndex=366|IndexInSheet=-1|OwnerPartId=-1|Location.X=109|Location.Y=416|Color=8388608|FontID=1|Text=U2|Name=Designator|ReadOnlyState=1
|RECORD=41|OwnerIndex=366|IndexInSheet=-1|OwnerPartId=-1|Location.X=109|Location.Y=374|Color=8388608|FontID=1|Text=SN74LVC3G07DCUR|Name=Comment
|RECORD=44|OwnerIndex=366
|RECORD=45|OwnerIndex=416|IndexInSheet=-1|Description=SOP, 8-Leads, Body 2.4x2.1mm, Pitch 0.5mm, IPC Medium Density|UseComponentLibrary=T|ModelName=DCU0008A_N|ModelType=PCBLIB|DatafileCount=1|ModelDatafileEntity0=DCU0008A_N|ModelDatafileKind0=PCBLib|IsCurrent=T|DatalinksLocked=T|DatabaseDatalinksLocked=T
|RECORD=46|OwnerIndex=417
|RECORD=48|OwnerIndex=417
|RECORD=41|OwnerIndex=419|IndexInSheet=-1|OwnerPartId=-1|Color=8388608|FontID=1|IsHidden=T|Text=2D|Name=Available Preview Images
|RECORD=45|OwnerIndex=416|IndexInSheet=-1|Description=SOP, 8-Leads, Body 2.4x2.1mm, Pitch 0.5mm, IPC Low Density|UseComponentLibrary=T|ModelName=DCU0008A_M|ModelType=PCBLIB|DatafileCount=1|ModelDatafileEntity0=DCU0008A_M|ModelDatafileKind0=PCBLib|DatalinksLocked=T|DatabaseDatalinksLocked=T
|RECORD=46|OwnerIndex=421
|RECORD=48|OwnerIndex=421
|RECORD=41|OwnerIndex=423|IndexInSheet=-1|OwnerPartId=-1|Color=8388608|FontID=1|IsHidden=T|Text=2D|Name=Available Preview Images
|RECORD=45|OwnerIndex=416|IndexInSheet=-1|Description=SOP, 8-Leads, Body 2.4x2.1mm, Pitch 0.5mm, IPC High Density|UseComponentLibrary=T|ModelName=DCU0008A_L|ModelType=PCBLIB|DatafileCount=1|ModelDatafileEntity0=DCU0008A_L|ModelDatafileKind0=PCBLib|DatalinksLocked=T|DatabaseDatalinksLocked=T
|RECORD=46|OwnerIndex=425
|RECORD=48|OwnerIndex=425
|RECORD=41|OwnerIndex=427|IndexInSheet=-1|OwnerPartId=-1|Color=8388608|FontID=1|IsHidden=T|Text=2D|Name=Available Preview Images
|RECORD=1|LibReference=TI-SN74XXX3G0X-XX-8|ComponentDescription=Triple Buffer/Driver With Open-Drain Output, DCU0008A, LARGE T&R|PartCount=5|DisplayModeCount=1|IndexInSheet=48|OwnerPartId=-1|Location.X=110|Location.Y=350|CurrentPartId=3|LibraryPath=*|SourceLibraryName=Altium Content Vault|TargetFileName=*|AreaColor=11599871|Color=128|PartIDLocked=F|DesignItemId=CMP-0859-00615-3|AllPinCount=8
|RECORD=2|OwnerIndex=429|OwnerPartId=3|FormalType=1|Electrical=3|PinConglomerate=48|PinLength=20|Location.X=140|Location.Y=330|Name=3Y|Designator=2|SwapIDPart=Ž&Ž2|PinPropagationDelay=0.000000E+000
|RECORD=2|OwnerIndex=429|OwnerPartId=3|FormalType=1|PinConglomerate=50|PinLength=20|Location.X=110|Location.Y=330|Name=3A|Designator=6|SwapIDPart=Ž&Ž2|PinPropagationDelay=0.000000E+000
|RECORD=13|OwnerIndex=429|IsNotAccesible=T|IndexInSheet=2|OwnerPartId=3|Location.X=110|Location.Y=345|Corner.X=140|Corner.Y=330|LineWidth=1|Color=16711680
|RECORD=13|OwnerIndex=429|IsNotAccesible=T|IndexInSheet=3|OwnerPartId=3|Location.X=110|Location.Y=315|Corner.X=140|Corner.Y=330|LineWidth=1|Color=16711680
|RECORD=13|OwnerIndex=429|IsNotAccesible=T|IndexInSheet=4|OwnerPartId=3|Location.X=110|Location.Y=315|Corner.X=110|Corner.Y=345|LineWidth=1|Color=16711680
|RECORD=2|OwnerIndex=429|OwnerPartId=2|FormalType=1|Electrical=3|PinConglomerate=48|PinLength=20|Location.X=140|Location.Y=330|Name=2Y|Designator=5|SwapIDPart=Ž&Ž2|PinPropagationDelay=0.000000E+000
|RECORD=2|OwnerIndex=429|OwnerPartId=2|FormalType=1|PinConglomerate=50|PinLength=20|Location.X=110|Location.Y=330|Name=2A|Designator=3|SwapIDPart=Ž&Ž2|PinPropagationDelay=0.000000E+000
|RECORD=13|OwnerIndex=429|IsNotAccesible=T|IndexInSheet=7|OwnerPartId=2|Location.X=110|Location.Y=345|Corner.X=140|Corner.Y=330|LineWidth=1|Color=16711680
|RECORD=13|OwnerIndex=429|IsNotAccesible=T|IndexInSheet=8|OwnerPartId=2|Location.X=110|Location.Y=315|Corner.X=140|Corner.Y=330|LineWidth=1|Color=16711680
|RECORD=13|OwnerIndex=429|IsNotAccesible=T|IndexInSheet=9|OwnerPartId=2|Location.X=110|Location.Y=315|Corner.X=110|Corner.Y=345|LineWidth=1|Color=16711680
|RECORD=14|OwnerIndex=429|IsNotAccesible=T|IndexInSheet=10|OwnerPartId=4|Location.X=110|Location.Y=330|Corner.X=170|Corner.Y=350|Color=128|AreaColor=11599871|IsSolid=T
|RECORD=2|OwnerIndex=429|OwnerPartId=4|FormalType=1|Electrical=7|PinConglomerate=56|PinLength=20|Location.X=170|Location.Y=340|Name=GND|Designator=4|PinPropagationDelay=0.000000E+000
|RECORD=2|OwnerIndex=429|OwnerPartId=4|FormalType=1|Electrical=7|PinConglomerate=58|PinLength=20|Location.X=110|Location.Y=340|Name=VCC|Designator=8|PinPropagationDelay=0.000000E+000
|RECORD=2|OwnerIndex=429|OwnerPartId=1|FormalType=1|Electrical=3|PinConglomerate=48|PinLength=20|Location.X=140|Location.Y=330|Name=1Y|Designator=7|SwapIDPart=Ž&Ž2|PinPropagationDelay=0.000000E+000
|RECORD=2|OwnerIndex=429|OwnerPartId=1|FormalType=1|PinConglomerate=50|PinLength=20|Location.X=110|Location.Y=330|Name=1A|Designator=1|SwapIDPart=Ž&Ž2|PinPropagationDelay=0.000000E+000
|RECORD=13|OwnerIndex=429|IsNotAccesible=T|IndexInSheet=15|OwnerPartId=1|Location.X=110|Location.Y=345|Corner.X=140|Corner.Y=330|LineWidth=1|Color=16711680
|RECORD=13|OwnerIndex=429|IsNotAccesible=T|IndexInSheet=16|OwnerPartId=1|Location.X=110|Location.Y=315|Corner.X=140|Corner.Y=330|LineWidth=1|Color=16711680
|RECORD=13|OwnerIndex=429|IsNotAccesible=T|IndexInSheet=17|OwnerPartId=1|Location.X=110|Location.Y=315|Corner.X=110|Corner.Y=345|LineWidth=1|Color=16711680
|RECORD=41|OwnerIndex=429|IndexInSheet=18|OwnerPartId=-1|Location.X=88|Location.Y=365|Color=8388608|FontID=1|IsHidden=T|Text=SN74LVC3G07|Name=Generic Part Number
|RECORD=41|OwnerIndex=429|IndexInSheet=19|OwnerPartId=-1|Location.X=88|Location.Y=365|Color=8388608|FontID=1|IsHidden=T|Text=5.5|Name=VCC(Max)(V)
|RECORD=41|OwnerIndex=429|IndexInSheet=20|OwnerPartId=-1|Location.X=88|Location.Y=365|Color=8388608|FontID=1|IsHidden=T|Text=Non-Inverting Buffer/Driver|Name=Sub-Family
|RECORD=41|OwnerIndex=429|IndexInSheet=21|OwnerPartId=-1|Location.X=88|Location.Y=365|Color=8388608|FontID=1|IsHidden=T|Text=True|Name=Logic
|RECORD=41|OwnerIndex=429|IndexInSheet=22|OwnerPartId=-1|Location.X=88|Location.Y=365|Color=8388608|FontID=1|IsHidden=T|Text=DCU0008A|Name=PackageReference
|RECORD=41|OwnerIndex=429|IndexInSheet=23|OwnerPartId=-1|Location.X=88|Location.Y=365|Color=8388608|FontID=1|IsHidden=T|Text=8.3,4.8,4.2,3.4|Name=tpd @ Nom Voltage(Max)(ns)
|RECORD=41|OwnerIndex=429|IndexInSheet=24|OwnerPartId=-1|Location.X=88|Location.Y=365|Color=8388608|FontID=1|IsHidden=T|Text=CMOS|Name=Output Type
|RECORD=41|OwnerIndex=429|IndexInSheet=25|OwnerPartId=-1|Location.X=88|Location.Y=365|Color=8388608|FontID=1|IsHidden=T|Text=150|Name=F @ Nom Voltage(Max)(Mhz)
|RECORD=41|OwnerIndex=429|IndexInSheet=26|OwnerPartId=-1|Location.X=88|Location.Y=365|Color=8388608|FontID=1|IsHidden=T|Text=LVC|Name=Technology Family
|RECORD=41|OwnerIndex=429|IndexInSheet=27|OwnerPartId=-1|Location.X=88|Location.Y=365|Color=8388608|FontID=1|IsHidden=T|Text=0.01|Name=ICC @ Nom Voltage(Max)(mA)
|RECORD=41|OwnerIndex=429|IndexInSheet=28|OwnerPartId=-1|Location.X=88|Location.Y=365|Color=8388608|FontID=1|IsHidden=T|Text=1.8,2.5,3.3,5|Name=Voltage(Nom)(V)
|RECORD=41|OwnerIndex=429|IndexInSheet=29|OwnerPartId=-1|Location.X=88|Location.Y=365|Color=8388608|FontID=1|IsHidden=T|Text=No|Name=Schmitt Trigger
|RECORD=41|OwnerIndex=429|IndexInSheet=30|OwnerPartId=-1|Location.X=88|Location.Y=365|Color=8388608|FontID=1|IsHidden=T|Text=Texas Instruments|Name=Manufacturer
|RECORD=41|OwnerIndex=429|IndexInSheet=31|OwnerPartId=-1|Location.X=88|Location.Y=365|Color=8388608|FontID=1|IsHidden=T|Text=1.65|Name=VCC(Min)(V)
|RECORD=41|OwnerIndex=429|IndexInSheet=32|OwnerPartId=-1|Location.X=88|Location.Y=365|Color=8388608|FontID=1|IsHidden=T|Text=No|Name=3-State Output
|RECORD=41|OwnerIndex=429|IndexInSheet=33|OwnerPartId=-1|Location.X=88|Location.Y=365|Color=8388608|FontID=1|IsHidden=T|Text=3|Name=Bits(#)
|RECORD=41|OwnerIndex=429|IndexInSheet=34|OwnerPartId=-1|Location.X=88|Location.Y=365|Color=8388608|FontID=1|IsHidden=T|Text=SCES365K|Name=DatasheetVersion
|RECORD=41|OwnerIndex=429|IndexInSheet=35|OwnerPartId=-1|Location.X=88|Location.Y=365|Color=8388608|FontID=1|IsHidden=T|Text=CMOS/TTL|Name=Input Type
|RECORD=41|OwnerIndex=429|IndexInSheet=36|OwnerPartId=-1|Location.X=88|Location.Y=365|Color=8388608|FontID=1|IsHidden=T|Text=Catalog|Name=Rating
|RECORD=41|OwnerIndex=429|IndexInSheet=37|OwnerPartId=-1|Location.X=88|Location.Y=365|Color=8388608|FontID=1|IsHidden=T|Text=32/-32|Name=Output Drive (IOL/IOH)(Max)(mA)
|RECORD=41|OwnerIndex=429|IndexInSheet=38|OwnerPartId=-1|Location.X=88|Location.Y=365|Color=8388608|FontID=1|IsHidden=T|Text=-40 to 125,-40 to 85|Name=Operating Temperature Range(C)
|RECORD=34|OwnerIndex=429|IndexInSheet=-1|OwnerPartId=-1|Location.X=109|Location.Y=346|Color=8388608|FontID=1|Text=U2|Name=Designator|ReadOnlyState=1
|RECORD=41|OwnerIndex=429|IndexInSheet=-1|OwnerPartId=-1|Location.X=109|Location.Y=304|Color=8388608|FontID=1|Text=SN74LVC3G07DCUR|Name=Comment
|RECORD=44|OwnerIndex=429
|RECORD=45|OwnerIndex=479|IndexInSheet=-1|Description=SOP, 8-Leads, Body 2.4x2.1mm, Pitch 0.5mm, IPC Medium Density|UseComponentLibrary=T|ModelName=DCU0008A_N|ModelType=PCBLIB|DatafileCount=1|ModelDatafileEntity0=DCU0008A_N|ModelDatafileKind0=PCBLib|IsCurrent=T|DatalinksLocked=T|DatabaseDatalinksLocked=T
|RECORD=46|OwnerIndex=480
|RECORD=48|OwnerIndex=480
|RECORD=41|OwnerIndex=482|IndexInSheet=-1|OwnerPartId=-1|Color=8388608|FontID=1|IsHidden=T|Text=2D|Name=Available Preview Images
|RECORD=45|OwnerIndex=479|IndexInSheet=-1|Description=SOP, 8-Leads, Body 2.4x2.1mm, Pitch 0.5mm, IPC Low Density|UseComponentLibrary=T|ModelName=DCU0008A_M|ModelType=PCBLIB|DatafileCount=1|ModelDatafileEntity0=DCU0008A_M|ModelDatafileKind0=PCBLib|DatalinksLocked=T|DatabaseDatalinksLocked=T
|RECORD=46|OwnerIndex=484
|RECORD=48|OwnerIndex=484
|RECORD=41|OwnerIndex=486|IndexInSheet=-1|OwnerPartId=-1|Color=8388608|FontID=1|IsHidden=T|Text=2D|Name=Available Preview Images
|RECORD=45|OwnerIndex=479|IndexInSheet=-1|Description=SOP, 8-Leads, Body 2.4x2.1mm, Pitch 0.5mm, IPC High Density|UseComponentLibrary=T|ModelName=DCU0008A_L|ModelType=PCBLIB|DatafileCount=1|ModelDatafileEntity0=DCU0008A_L|ModelDatafileKind0=PCBLib|DatalinksLocked=T|DatabaseDatalinksLocked=T
|RECORD=46|OwnerIndex=488
|RECORD=48|OwnerIndex=488
|RECORD=41|OwnerIndex=490|IndexInSheet=-1|OwnerPartId=-1|Color=8388608|FontID=1|IsHidden=T|Text=2D|Name=Available Preview Images
|RECORD=1|LibReference=TI-SN74XXX3G0X-XX-8|ComponentDescription=Triple Buffer/Driver With Open-Drain Output, DCU0008A, LARGE T&R|PartCount=5|DisplayModeCount=1|IndexInSheet=49|OwnerPartId=-1|Location.X=110|Location.Y=280|CurrentPartId=4|LibraryPath=*|SourceLibraryName=Altium Content Vault|TargetFileName=*|AreaColor=11599871|Color=128|PartIDLocked=F|DesignItemId=CMP-0859-00615-3|AllPinCount=8
|RECORD=2|OwnerIndex=492|OwnerPartId=3|FormalType=1|Electrical=3|PinConglomerate=48|PinLength=20|Location.X=140|Location.Y=260|Name=3Y|Designator=2|SwapIDPart=Ž&Ž2|PinPropagationDelay=0.000000E+000
|RECORD=2|OwnerIndex=492|OwnerPartId=3|FormalType=1|PinConglomerate=50|PinLength=20|Location.X=110|Location.Y=260|Name=3A|Designator=6|SwapIDPart=Ž&Ž2|PinPropagationDelay=0.000000E+000
|RECORD=13|OwnerIndex=492|IsNotAccesible=T|IndexInSheet=2|OwnerPartId=3|Location.X=110|Location.Y=275|Corner.X=140|Corner.Y=260|LineWidth=1|Color=16711680
|RECORD=13|OwnerIndex=492|IsNotAccesible=T|IndexInSheet=3|OwnerPartId=3|Location.X=110|Location.Y=245|Corner.X=140|Corner.Y=260|LineWidth=1|Color=16711680
|RECORD=13|OwnerIndex=492|IsNotAccesible=T|IndexInSheet=4|OwnerPartId=3|Location.X=110|Location.Y=245|Corner.X=110|Corner.Y=275|LineWidth=1|Color=16711680
|RECORD=2|OwnerIndex=492|OwnerPartId=2|FormalType=1|Electrical=3|PinConglomerate=48|PinLength=20|Location.X=140|Location.Y=260|Name=2Y|Designator=5|SwapIDPart=Ž&Ž2|PinPropagationDelay=0.000000E+000
|RECORD=2|OwnerIndex=492|OwnerPartId=2|FormalType=1|PinConglomerate=50|PinLength=20|Location.X=110|Location.Y=260|Name=2A|Designator=3|SwapIDPart=Ž&Ž2|PinPropagationDelay=0.000000E+000
|RECORD=13|OwnerIndex=492|IsNotAccesible=T|IndexInSheet=7|OwnerPartId=2|Location.X=110|Location.Y=275|Corner.X=140|Corner.Y=260|LineWidth=1|Color=16711680
|RECORD=13|OwnerIndex=492|IsNotAccesible=T|IndexInSheet=8|OwnerPartId=2|Location.X=110|Location.Y=245|Corner.X=140|Corner.Y=260|LineWidth=1|Color=16711680
|RECORD=13|OwnerIndex=492|IsNotAccesible=T|IndexInSheet=9|OwnerPartId=2|Location.X=110|Location.Y=245|Corner.X=110|Corner.Y=275|LineWidth=1|Color=16711680
|RECORD=14|OwnerIndex=492|IsNotAccesible=T|IndexInSheet=10|OwnerPartId=4|Location.X=110|Location.Y=260|Corner.X=170|Corner.Y=280|Color=128|AreaColor=11599871|IsSolid=T
|RECORD=2|OwnerIndex=492|OwnerPartId=4|FormalType=1|Electrical=7|PinConglomerate=56|PinLength=20|Location.X=170|Location.Y=270|Name=GND|Designator=4|PinPropagationDelay=0.000000E+000
|RECORD=2|OwnerIndex=492|OwnerPartId=4|FormalType=1|Electrical=7|PinConglomerate=58|PinLength=20|Location.X=110|Location.Y=270|Name=VCC|Designator=8|PinPropagationDelay=0.000000E+000
|RECORD=2|OwnerIndex=492|OwnerPartId=1|FormalType=1|Electrical=3|PinConglomerate=48|PinLength=20|Location.X=140|Location.Y=260|Name=1Y|Designator=7|SwapIDPart=Ž&Ž2|PinPropagationDelay=0.000000E+000
|RECORD=2|OwnerIndex=492|OwnerPartId=1|FormalType=1|PinConglomerate=50|PinLength=20|Location.X=110|Location.Y=260|Name=1A|Designator=1|SwapIDPart=Ž&Ž2|PinPropagationDelay=0.000000E+000
|RECORD=13|OwnerIndex=492|IsNotAccesible=T|IndexInSheet=15|OwnerPartId=1|Location.X=110|Location.Y=275|Corner.X=140|Corner.Y=260|LineWidth=1|Color=16711680
|RECORD=13|OwnerIndex=492|IsNotAccesible=T|IndexInSheet=16|OwnerPartId=1|Location.X=110|Location.Y=245|Corner.X=140|Corner.Y=260|LineWidth=1|Color=16711680
|RECORD=13|OwnerIndex=492|IsNotAccesible=T|IndexInSheet=17|OwnerPartId=1|Location.X=110|Location.Y=245|Corner.X=110|Corner.Y=275|LineWidth=1|Color=16711680
|RECORD=41|OwnerIndex=492|IndexInSheet=18|OwnerPartId=-1|Location.X=88|Location.Y=295|Color=8388608|FontID=1|IsHidden=T|Text=SN74LVC3G07|Name=Generic Part Number
|RECORD=41|OwnerIndex=492|IndexInSheet=19|OwnerPartId=-1|Location.X=88|Location.Y=295|Color=8388608|FontID=1|IsHidden=T|Text=5.5|Name=VCC(Max)(V)
|RECORD=41|OwnerIndex=492|IndexInSheet=20|OwnerPartId=-1|Location.X=88|Location.Y=295|Color=8388608|FontID=1|IsHidden=T|Text=Non-Inverting Buffer/Driver|Name=Sub-Family
|RECORD=41|OwnerIndex=492|IndexInSheet=21|OwnerPartId=-1|Location.X=88|Location.Y=295|Color=8388608|FontID=1|IsHidden=T|Text=True|Name=Logic
|RECORD=41|OwnerIndex=492|IndexInSheet=22|OwnerPartId=-1|Location.X=88|Location.Y=295|Color=8388608|FontID=1|IsHidden=T|Text=DCU0008A|Name=PackageReference
|RECORD=41|OwnerIndex=492|IndexInSheet=23|OwnerPartId=-1|Location.X=88|Location.Y=295|Color=8388608|FontID=1|IsHidden=T|Text=8.3,4.8,4.2,3.4|Name=tpd @ Nom Voltage(Max)(ns)
|RECORD=41|OwnerIndex=492|IndexInSheet=24|OwnerPartId=-1|Location.X=88|Location.Y=295|Color=8388608|FontID=1|IsHidden=T|Text=CMOS|Name=Output Type
|RECORD=41|OwnerIndex=492|IndexInSheet=25|OwnerPartId=-1|Location.X=88|Location.Y=295|Color=8388608|FontID=1|IsHidden=T|Text=150|Name=F @ Nom Voltage(Max)(Mhz)
|RECORD=41|OwnerIndex=492|IndexInSheet=26|OwnerPartId=-1|Location.X=88|Location.Y=295|Color=8388608|FontID=1|IsHidden=T|Text=LVC|Name=Technology Family
|RECORD=41|OwnerIndex=492|IndexInSheet=27|OwnerPartId=-1|Location.X=88|Location.Y=295|Color=8388608|FontID=1|IsHidden=T|Text=0.01|Name=ICC @ Nom Voltage(Max)(mA)
|RECORD=41|OwnerIndex=492|IndexInSheet=28|OwnerPartId=-1|Location.X=88|Location.Y=295|Color=8388608|FontID=1|IsHidden=T|Text=1.8,2.5,3.3,5|Name=Voltage(Nom)(V)
|RECORD=41|OwnerIndex=492|IndexInSheet=29|OwnerPartId=-1|Location.X=88|Location.Y=295|Color=8388608|FontID=1|IsHidden=T|Text=No|Name=Schmitt Trigger
|RECORD=41|OwnerIndex=492|IndexInSheet=30|OwnerPartId=-1|Location.X=88|Location.Y=295|Color=8388608|FontID=1|IsHidden=T|Text=Texas Instruments|Name=Manufacturer
|RECORD=41|OwnerIndex=492|IndexInSheet=31|OwnerPartId=-1|Location.X=88|Location.Y=295|Color=8388608|FontID=1|IsHidden=T|Text=1.65|Name=VCC(Min)(V)
|RECORD=41|OwnerIndex=492|IndexInSheet=32|OwnerPartId=-1|Location.X=88|Location.Y=295|Color=8388608|FontID=1|IsHidden=T|Text=No|Name=3-State Output
|RECORD=41|OwnerIndex=492|IndexInSheet=33|OwnerPartId=-1|Location.X=88|Location.Y=295|Color=8388608|FontID=1|IsHidden=T|Text=3|Name=Bits(#)
|RECORD=41|OwnerIndex=492|IndexInSheet=34|OwnerPartId=-1|Location.X=88|Location.Y=295|Color=8388608|FontID=1|IsHidden=T|Text=SCES365K|Name=DatasheetVersion
|RECORD=41|OwnerIndex=492|IndexInSheet=35|OwnerPartId=-1|Location.X=88|Location.Y=295|Color=8388608|FontID=1|IsHidden=T|Text=CMOS/TTL|Name=Input Type
|RECORD=41|OwnerIndex=492|IndexInSheet=36|OwnerPartId=-1|Location.X=88|Location.Y=295|Color=8388608|FontID=1|IsHidden=T|Text=Catalog|Name=Rating
|RECORD=41|OwnerIndex=492|IndexInSheet=37|OwnerPartId=-1|Location.X=88|Location.Y=295|Color=8388608|FontID=1|IsHidden=T|Text=32/-32|Name=Output Drive (IOL/IOH)(Max)(mA)
|RECORD=41|OwnerIndex=492|IndexInSheet=38|OwnerPartId=-1|Location.X=88|Location.Y=295|Color=8388608|FontID=1|IsHidden=T|Text=-40 to 125,-40 to 85|Name=Operating Temperature Range(C)
|RECORD=34|OwnerIndex=492|IndexInSheet=-1|OwnerPartId=-1|Location.X=110|Location.Y=280|Color=8388608|FontID=1|Text=U2|Name=Designator|ReadOnlyState=1
|RECORD=41|OwnerIndex=492|IndexInSheet=-1|OwnerPartId=-1|Location.X=109|Location.Y=234|Color=8388608|FontID=1|Text=SN74LVC3G07DCUR|Name=Comment
|RECORD=44|OwnerIndex=492
|RECORD=45|OwnerIndex=542|IndexInSheet=-1|Description=SOP, 8-Leads, Body 2.4x2.1mm, Pitch 0.5mm, IPC Medium Density|UseComponentLibrary=T|ModelName=DCU0008A_N|ModelType=PCBLIB|DatafileCount=1|ModelDatafileEntity0=DCU0008A_N|ModelDatafileKind0=PCBLib|IsCurrent=T|DatalinksLocked=T|DatabaseDatalinksLocked=T
|RECORD=46|OwnerIndex=543
|RECORD=48|OwnerIndex=543
|RECORD=41|OwnerIndex=545|IndexInSheet=-1|OwnerPartId=-1|Color=8388608|FontID=1|IsHidden=T|Text=2D|Name=Available Preview Images
|RECORD=45|OwnerIndex=542|IndexInSheet=-1|Description=SOP, 8-Leads, Body 2.4x2.1mm, Pitch 0.5mm, IPC Low Density|UseComponentLibrary=T|ModelName=DCU0008A_M|ModelType=PCBLIB|DatafileCount=1|ModelDatafileEntity0=DCU0008A_M|ModelDatafileKind0=PCBLib|DatalinksLocked=T|DatabaseDatalinksLocked=T
|RECORD=46|OwnerIndex=547
|RECORD=48|OwnerIndex=547
|RECORD=41|OwnerIndex=549|IndexInSheet=-1|OwnerPartId=-1|Color=8388608|FontID=1|IsHidden=T|Text=2D|Name=Available Preview Images
|RECORD=45|OwnerIndex=542|IndexInSheet=-1|Description=SOP, 8-Leads, Body 2.4x2.1mm, Pitch 0.5mm, IPC High Density|UseComponentLibrary=T|ModelName=DCU0008A_L|ModelType=PCBLIB|DatafileCount=1|ModelDatafileEntity0=DCU0008A_L|ModelDatafileKind0=PCBLib|DatalinksLocked=T|DatabaseDatalinksLocked=T
|RECORD=46|OwnerIndex=551
|RECORD=48|OwnerIndex=551
|RECORD=41|OwnerIndex=553|IndexInSheet=-1|OwnerPartId=-1|Color=8388608|FontID=1|IsHidden=T|Text=2D|Name=Available Preview Images
|RECORD=22|IndexInSheet=50|OwnerPartId=-1|Location.X=90|Location.Y=330|Color=255|Orientation=1|Symbol=Thin Cross|IsActive=T|SuppressAll=T
|RECORD=22|IndexInSheet=51|OwnerPartId=-1|Location.X=160|Location.Y=330|Color=255|Orientation=1|Symbol=Thin Cross|IsActive=T|SuppressAll=T
|RECORD=17|IndexInSheet=52|OwnerPartId=-1|Style=2|ShowNetName=T|Location.X=70|Location.Y=270|Orientation=1|Color=128|FontID=1|Text=VCC
|RECORD=17|IndexInSheet=53|OwnerPartId=-1|Style=4|ShowNetName=F|Location.X=190|Location.Y=270|Orientation=3|Color=128|FontID=1|Text=GND
|RECORD=1|LibReference=b4654b650e69147ec39a6b967a45e02|ComponentDescription=None|PartCount=2|DisplayModeCount=1|IndexInSheet=54|OwnerPartId=-1|Location.X=70|Location.Y=270|CurrentPartId=1|LibraryPath=*|SourceLibraryName=Altium Content Vault|TargetFileName=*|AreaColor=11599871|Color=128|PartIDLocked=T|DesignItemId=CMP-14477-000330-2|AllPinCount=2
|RECORD=2|OwnerIndex=559|OwnerPartId=1|Electrical=4|PinConglomerate=33|PinLength=7|Location.X=70|Location.Y=263|Name=1|Designator=1|PinPropagationDelay=0.000000E+000
|RECORD=2|OwnerIndex=559|OwnerPartId=1|Electrical=4|PinConglomerate=35|PinLength=6|Location.X=70|Location.Y=256|Name=2|Designator=2|PinPropagationDelay=0.000000E+000
|RECORD=13|OwnerIndex=559|IsNotAccesible=T|IndexInSheet=2|OwnerPartId=1|Location.X=80|Location.Y=263|Corner.X=60|Corner.Y=263|LineWidth=1|Color=16711680
|RECORD=13|OwnerIndex=559|IsNotAccesible=T|IndexInSheet=3|OwnerPartId=1|Location.X=80|Location.Y=257|Corner.X=60|Corner.Y=257|LineWidth=1|Color=16711680
|RECORD=13|OwnerIndex=559|IsNotAccesible=T|IndexInSheet=4|OwnerPartId=1|Location.X=70|Location.Y=263|Corner.X=70|Corner.Y=266|LineWidth=1|Color=16711680
|RECORD=13|OwnerIndex=559|IsNotAccesible=T|IndexInSheet=5|OwnerPartId=1|Location.X=70|Location.Y=256|Corner.X=70|Corner.Y=255|LineWidth=1|Color=16711680
|RECORD=41|OwnerIndex=559|IndexInSheet=6|OwnerPartId=-1|Location.X=59|Location.Y=272|Color=8388608|FontID=1|IsHidden=T|Text=Yes|Name=RoHS Compliant
|RECORD=41|OwnerIndex=559|IndexInSheet=7|OwnerPartId=-1|Location.X=59|Location.Y=272|Color=8388608|FontID=1|IsHidden=T|Text=SMD/SMT|Name=Termination
|RECORD=41|OwnerIndex=559|IndexInSheet=8|OwnerPartId=-1|Location.X=59|Location.Y=272|Color=8388608|FontID=1|IsHidden=T|Text=Tape and Reel|Name=Packaging
|RECORD=41|OwnerIndex=559|IndexInSheet=9|OwnerPartId=-1|Location.X=59|Location.Y=272|Color=8388608|FontID=1|IsHidden=T|Text=50V|Name=Voltage Rating (DC)
|RECORD=41|OwnerIndex=559|IndexInSheet=10|OwnerPartId=-1|Location.X=59|Location.Y=272|Color=8388608|FontID=1|IsHidden=T|Text=100nF|Name=Capacitance
|RECORD=41|OwnerIndex=559|IndexInSheet=11|OwnerPartId=-1|Location.X=59|Location.Y=272|Color=8388608|FontID=1|IsHidden=T|Text=0.5mm|Name=Height
|RECORD=41|OwnerIndex=559|IndexInSheet=12|OwnerPartId=-1|Location.X=59|Location.Y=272|Color=8388608|FontID=1|IsHidden=T|Text=Halogen Free|Name=Halogen Free
|RECORD=41|OwnerIndex=559|IndexInSheet=13|OwnerPartId=-1|Location.X=59|Location.Y=272|Color=8388608|FontID=1|IsHidden=T|Text=1005|Name=Case Code (Metric)
|RECORD=41|OwnerIndex=559|IndexInSheet=14|OwnerPartId=-1|Location.X=59|Location.Y=272|Color=8388608|FontID=1|IsHidden=T|Text=0.02inch|Name=Width
|RECORD=41|OwnerIndex=559|IndexInSheet=15|OwnerPartId=-1|Location.X=59|Location.Y=272|Color=8388608|FontID=1|IsHidden=T|Text=85°C|Name=Max Operating Temperature
|RECORD=41|OwnerIndex=559|IndexInSheet=16|OwnerPartId=-1|Location.X=59|Location.Y=272|Color=8388608|FontID=1|IsHidden=T|Text=50V|Name=Voltage Rating
|RECORD=41|OwnerIndex=559|IndexInSheet=17|OwnerPartId=-1|Location.X=59|Location.Y=272|Color=8388608|FontID=1|IsHidden=T|Text=-55°C|Name=Min Operating Temperature
|RECORD=41|OwnerIndex=559|IndexInSheet=18|OwnerPartId=-1|Location.X=59|Location.Y=272|Color=8388608|FontID=1|IsHidden=T|Text=10000|Name=Package Quantity
|RECORD=41|OwnerIndex=559|IndexInSheet=19|OwnerPartId=-1|Location.X=59|Location.Y=272|Color=8388608|FontID=1|IsHidden=T|Text=0402|Name=Case/Package
|RECORD=41|OwnerIndex=559|IndexInSheet=20|OwnerPartId=-1|Location.X=59|Location.Y=272|Color=8388608|FontID=1|IsHidden=T|Text=0402|Name=Case Code (Imperial)
|RECORD=41|OwnerIndex=559|IndexInSheet=21|OwnerPartId=-1|Location.X=59|Location.Y=272|Color=8388608|FontID=1|IsHidden=T|Text=X5R|Name=Dielectric
|RECORD=41|OwnerIndex=559|IndexInSheet=22|OwnerPartId=-1|Location.X=59|Location.Y=272|Color=8388608|FontID=1|IsHidden=T|Text=10%|Name=Tolerance
|RECORD=41|OwnerIndex=559|IndexInSheet=23|OwnerPartId=-1|Location.X=59|Location.Y=272|Color=8388608|FontID=1|IsHidden=T|Text=0.039inch|Name=Length
|RECORD=41|OwnerIndex=559|IndexInSheet=24|OwnerPartId=-1|Location.X=59|Location.Y=272|Color=8388608|FontID=1|IsHidden=T|Text=0.022inch|Name=Thickness
|RECORD=41|OwnerIndex=559|IndexInSheet=25|OwnerPartId=-1|Location.X=59|Location.Y=272|Color=8388608|FontID=1|IsHidden=T|Text=Surface Mount|Name=Mount
|RECORD=34|OwnerIndex=559|IndexInSheet=-1|OwnerPartId=-1|Location.X=81|Location.Y=257|Color=8388608|FontID=1|Text=C6|Name=Designator|ReadOnlyState=1
|RECORD=41|OwnerIndex=559|IndexInSheet=-1|OwnerPartId=1|Location.X=81|Location.Y=247|Color=8388608|FontID=1|Text=100nF|Name=Comment
|RECORD=44|OwnerIndex=559
|RECORD=45|OwnerIndex=590|IndexInSheet=-1|UseComponentLibrary=T|ModelName=FP-0402-L_1_0_0_05-W_0_5-IPC_B|ModelType=PCBLIB|DatafileCount=1|ModelDatafileEntity0=FP-0402-L_1_0_0_05-W_0_5-IPC_B|ModelDatafileKind0=PCBLib|IsCurrent=T|DatalinksLocked=T|DatabaseDatalinksLocked=T
|RECORD=46|OwnerIndex=591
|RECORD=48|OwnerIndex=591
|RECORD=45|OwnerIndex=590|IndexInSheet=-1|UseComponentLibrary=T|ModelName=FP-0402-L_1_0_0_05-W_0_5-IPC_A|ModelType=PCBLIB|DatafileCount=1|ModelDatafileEntity0=FP-0402-L_1_0_0_05-W_0_5-IPC_A|ModelDatafileKind0=PCBLib|DatalinksLocked=T|DatabaseDatalinksLocked=T
|RECORD=46|OwnerIndex=594
|RECORD=48|OwnerIndex=594
|RECORD=45|OwnerIndex=590|IndexInSheet=-1|UseComponentLibrary=T|ModelName=FP-0402-L_1_0_0_05-W_0_5-MFG|ModelType=PCBLIB|DatafileCount=1|ModelDatafileEntity0=FP-0402-L_1_0_0_05-W_0_5-MFG|ModelDatafileKind0=PCBLib|DatalinksLocked=T|DatabaseDatalinksLocked=T
|RECORD=46|OwnerIndex=597
|RECORD=48|OwnerIndex=597
|RECORD=45|OwnerIndex=590|IndexInSheet=-1|UseComponentLibrary=T|ModelName=UMK105BJ104_V-F|ModelType=SIM|IsCurrent=T|DatalinksLocked=T|DatabaseDatalinksLocked=T
|RECORD=46|OwnerIndex=600
|RECORD=48|OwnerIndex=600
|RECORD=41|OwnerIndex=602|IndexInSheet=-1|OwnerPartId=-1|Color=8388608|FontID=1|IsHidden=T|Text=General|Name=Kind
|RECORD=41|OwnerIndex=602|IndexInSheet=-1|OwnerPartId=-1|Color=8388608|FontID=1|IsHidden=T|Text=Spice Subcircuit|Name=SubKind
|RECORD=41|OwnerIndex=602|IndexInSheet=-1|OwnerPartId=-1|Color=8388608|FontID=1|IsHidden=T|Name=Spice Prefix
|RECORD=41|OwnerIndex=602|IndexInSheet=-1|OwnerPartId=-1|Color=8388608|FontID=1|IsHidden=T|Name=Excluded Parts
|RECORD=41|OwnerIndex=602|IndexInSheet=-1|OwnerPartId=-1|Color=8388608|FontID=1|IsHidden=T|Name=Netlist
|RECORD=41|OwnerIndex=602|IndexInSheet=-1|OwnerPartId=-1|Color=8388608|FontID=1|IsHidden=T|Text=document_sim_cache\PCDZUYPJ\0|Name=SimulationCacheLocation|ReadOnlyState=3
|RECORD=45|OwnerIndex=590|IndexInSheet=-1|UseComponentLibrary=T|ModelName=FP-0402-L_1_0_0_05-W_0_5-IPC_C|ModelType=PCBLIB|DatafileCount=1|ModelDatafileEntity0=FP-0402-L_1_0_0_05-W_0_5-IPC_C|ModelDatafileKind0=PCBLib|DatalinksLocked=T|DatabaseDatalinksLocked=T
|RECORD=46|OwnerIndex=609
|RECORD=48|OwnerIndex=609
|RECORD=17|IndexInSheet=55|OwnerPartId=-1|Style=4|ShowNetName=F|Location.X=70|Location.Y=250|Orientation=3|Color=128|FontID=1|Text=GND
|RECORD=41|IndexInSheet=56|OwnerPartId=-1|Color=8388608|FontID=1|IsHidden=T|Text=|Name=SPICEModelCachePCDZUYPJ|ReadOnlyState=3
|RECORD=1|LibReference=GPS_ZED-F9T|ComponentDescription=Multi-band GNSS Receiver with Nanosecond-level Timing Accuracy|PartCount=4|DisplayModeCount=1|IndexInSheet=57|OwnerPartId=-1|Location.X=720|Location.Y=620|CurrentPartId=1|LibraryPath=*|SourceLibraryName=GNSS_Receiver_Library.IntLib|TargetFileName=*|AreaColor=11599871|Color=128|PartIDLocked=F|DesignItemId=GPS_ZED-F9T|AllPinCount=34
|RECORD=41|OwnerIndex=614|OwnerPartId=-1|Location.X=698|Location.Y=635|Color=8388608|FontID=1|IsHidden=T|Text=Digi-Key|Name=Supplier 1|ReadOnlyState=3
|RECORD=41|OwnerIndex=614|IndexInSheet=1|OwnerPartId=-1|Location.X=698|Location.Y=645|Color=8388608|FontID=1|IsHidden=T|Text=u-blox|Name=Manufacturer
|RECORD=41|OwnerIndex=614|IndexInSheet=2|OwnerPartId=-1|Location.X=698|Location.Y=645|Color=8388608|FontID=1|IsHidden=T|Text=ZED-F9T-00B|Name=Manufacturer Part Number
|RECORD=41|OwnerIndex=614|IndexInSheet=3|OwnerPartId=-1|Location.X=698|Location.Y=645|Color=8388608|FontID=1|IsHidden=T|Text=Yes|Name=RoHS
|RECORD=41|OwnerIndex=614|IndexInSheet=4|OwnerPartId=-1|Location.X=698|Location.Y=645|Color=8388608|FontID=1|IsHidden=T|Text=RF Receivers, Transceivers|Name=Category
|RECORD=41|OwnerIndex=614|IndexInSheet=5|OwnerPartId=-1|Location.X=698|Location.Y=645|Color=8388608|FontID=1|IsHidden=T|Text=826|Name=Stock 1|ReadOnlyState=3
|RECORD=41|OwnerIndex=614|IndexInSheet=6|OwnerPartId=-1|Location.X=698|Location.Y=645|Color=8388608|FontID=1|IsHidden=T|Text=1=199.00000, 10=198.80000, 50=180.89020 (USD)|Name=Pricing 1|ReadOnlyState=3
|RECORD=41|OwnerIndex=614|IndexInSheet=7|OwnerPartId=-1|Location.X=698|Location.Y=645|Color=8388608|FontID=1|IsHidden=T|Text=SMD/SMT|Name=Case/Package
|RECORD=41|OwnerIndex=614|IndexInSheet=8|OwnerPartId=-1|Location.X=698|Location.Y=645|Color=8388608|FontID=1|IsHidden=T|Text=-40°C|Name=Min Operating Temperature
|RECORD=41|OwnerIndex=614|IndexInSheet=9|OwnerPartId=-1|Location.X=698|Location.Y=645|Color=8388608|FontID=1|IsHidden=T|Text=85°C|Name=Max Operating Temperature
|RECORD=41|OwnerIndex=614|IndexInSheet=10|OwnerPartId=-1|Location.X=698|Location.Y=645|Color=8388608|FontID=1|IsHidden=T|Text=I2C,SPI,USB,UART|Name=Interface
|RECORD=41|OwnerIndex=614|IndexInSheet=11|OwnerPartId=-1|Location.X=698|Location.Y=645|Color=8388608|FontID=1|IsHidden=T|Text=Tape and Reel|Name=Packaging
|RECORD=41|OwnerIndex=614|IndexInSheet=12|OwnerPartId=-1|Location.X=698|Location.Y=645|Color=8388608|FontID=1|IsHidden=T|Text=-166dBm|Name=Sensitivity
|RECORD=41|OwnerIndex=614|IndexInSheet=13|OwnerPartId=-1|Location.X=698|Location.Y=645|Color=8388608|FontID=2|IsHidden=T|Text=https://www.u-blox.com/sites/default/files/ZED-F9T_ProductSummary_%28UBX-18011626%29.pdf?src-supplier=Digi-Key|Name=ComponentLink1URL
|RECORD=41|OwnerIndex=614|IndexInSheet=14|OwnerPartId=-1|Location.X=698|Location.Y=645|Color=8388608|FontID=2|IsHidden=T|Text=https://www.u-blox.com/sites/default/files/ZED-F9T_ProductSummary_%28UBX-18011626%29.pdf?src-supplier=Digi-Key|Name=ComponentLink1Description
|RECORD=41|OwnerIndex=614|IndexInSheet=15|OwnerPartId=-1|Location.X=720|Location.Y=620|Color=8388608|FontID=1|IsHidden=T|Text=672-1197-1-ND|Name=Supplier Part Number 1|ReadOnlyState=3
|RECORD=14|OwnerIndex=614|IsNotAccesible=T|IndexInSheet=16|OwnerPartId=2|Location.X=720|Location.Y=530|Corner.X=810|Corner.Y=620|Color=128|AreaColor=11599871|IsSolid=T
|RECORD=2|OwnerIndex=614|OwnerPartId=2|FormalType=1|Electrical=2|PinConglomerate=56|PinLength=20|Location.X=810|Location.Y=610|Name=VCC_RF|Designator=7|SwapIDPart=Ž&Ž||PinPropagationDelay=0.000000E+000
|RECORD=2|OwnerIndex=614|OwnerPartId=2|FormalType=1|PinConglomerate=58|PinLength=20|Location.X=720|Location.Y=610|Name=RF_IN|Designator=2|SwapIDPart=Ž&Ž||PinPropagationDelay=0.000000E+000
|RECORD=2|OwnerIndex=614|OwnerPartId=2|FormalType=1|PinConglomerate=58|PinLength=20|Location.X=720|Location.Y=580|Name=ANT_DETECT|Designator=4|SwapIDPart=Ž&Ž||PinPropagationDelay=0.000000E+000
|RECORD=2|OwnerIndex=614|OwnerPartId=2|FormalType=1|Electrical=2|PinConglomerate=58|PinLength=20|Location.X=720|Location.Y=570|Name=ANT_OFF|Designator=5|SwapIDPart=Ž&Ž||PinPropagationDelay=0.000000E+000
|RECORD=2|OwnerIndex=614|OwnerPartId=2|FormalType=1|PinConglomerate=58|PinLength=20|Location.X=720|Location.Y=560|Name=ANT_SHORT_N|Designator=6|SwapIDPart=Ž&Ž||PinPropagationDelay=0.000000E+000
|RECORD=2|OwnerIndex=614|OwnerPartId=2|FormalType=1|Electrical=2|PinConglomerate=56|PinLength=20|Location.X=810|Location.Y=540|Name=GEOFENCE_STAT|Designator=19|SwapIDPart=Ž&Ž||PinPropagationDelay=0.000000E+000
|RECORD=14|OwnerIndex=614|IsNotAccesible=T|IndexInSheet=23|OwnerPartId=3|Location.X=720|Location.Y=460|Corner.X=830|Corner.Y=620|Color=128|AreaColor=11599871|IsSolid=T
|RECORD=2|OwnerIndex=614|OwnerPartId=3|FormalType=1|PinConglomerate=58|PinLength=20|Location.X=720|Location.Y=610|Name=D_SEL|Designator=47|SwapIDPart=Ž&Ž||PinPropagationDelay=0.000000E+000
|RECORD=2|OwnerIndex=614|OwnerPartId=3|FormalType=1|Electrical=2|PinConglomerate=56|PinLength=20|Location.X=830|Location.Y=610|Name=TIMEPULSE|Designator=53|SwapIDPart=Ž&Ž||PinPropagationDelay=0.000000E+000
|RECORD=2|OwnerIndex=614|OwnerPartId=3|FormalType=1|Electrical=2|PinConglomerate=56|PinLength=20|Location.X=830|Location.Y=600|Name=TIMEPULSE2|Designator=54|SwapIDPart=Ž&Ž||PinPropagationDelay=0.000000E+000
|RECORD=2|OwnerIndex=614|OwnerPartId=3|FormalType=1|PinConglomerate=58|PinLength=20|Location.X=720|Location.Y=500|Name=RXD2|Designator=26|SwapIDPart=Ž&Ž||PinPropagationDelay=0.000000E+000
|RECORD=2|OwnerIndex=614|OwnerPartId=3|FormalType=1|Electrical=2|PinConglomerate=58|PinLength=20|Location.X=720|Location.Y=510|Name=TXD2|Designator=27|SwapIDPart=Ž&Ž||PinPropagationDelay=0.000000E+000
|RECORD=2|OwnerIndex=614|OwnerPartId=3|FormalType=1|Electrical=1|PinConglomerate=58|PinLength=20|Location.X=720|Location.Y=480|Name=USB_DM|Designator=39|SwapIDPart=Ž&Ž||PinPropagationDelay=0.000000E+000
|RECORD=2|OwnerIndex=614|OwnerPartId=3|FormalType=1|Electrical=1|PinConglomerate=58|PinLength=20|Location.X=720|Location.Y=470|Name=USB_DP|Designator=40|SwapIDPart=Ž&Ž||PinPropagationDelay=0.000000E+000
|RECORD=2|OwnerIndex=614|OwnerPartId=3|FormalType=1|Electrical=2|PinConglomerate=58|PinLength=20|Location.X=720|Location.Y=560|Name=TXD/SPI_MISO|Designator=42|SwapIDPart=Ž&Ž||PinPropagationDelay=0.000000E+000
|RECORD=2|OwnerIndex=614|OwnerPartId=3|FormalType=1|PinConglomerate=58|PinLength=20|Location.X=720|Location.Y=550|Name=RXD/SPI_MOSI|Designator=43|SwapIDPart=Ž&Ž||PinPropagationDelay=0.000000E+000
|RECORD=2|OwnerIndex=614|OwnerPartId=3|FormalType=1|Electrical=1|PinConglomerate=58|PinLength=20|Location.X=720|Location.Y=540|Name=SDA/SPI_CS_N|Designator=44|SwapIDPart=Ž&Ž||PinPropagationDelay=0.000000E+000
|RECORD=2|OwnerIndex=614|OwnerPartId=3|FormalType=1|Electrical=1|PinConglomerate=58|PinLength=20|Location.X=720|Location.Y=530|Name=SCL/SPI_CLK|Designator=45|SwapIDPart=Ž&Ž||PinPropagationDelay=0.000000E+000
|RECORD=2|OwnerIndex=614|OwnerPartId=3|FormalType=1|PinConglomerate=58|PinLength=20|Location.X=720|Location.Y=590|Name=EXTIN|Designator=51|SwapIDPart=Ž&Ž||PinPropagationDelay=0.000000E+000
|RECORD=2|OwnerIndex=614|OwnerPartId=3|FormalType=1|PinConglomerate=58|PinLength=20|Location.X=720|Location.Y=580|Name=EXTIN2|Designator=52|SwapIDPart=Ž&Ž||PinPropagationDelay=0.000000E+000
|RECORD=14|OwnerIndex=614|IsNotAccesible=T|IndexInSheet=37|OwnerPartId=1|Location.X=720|Location.Y=520|Corner.X=840|Corner.Y=620|Color=128|AreaColor=11599871|IsSolid=T
|RECORD=2|OwnerIndex=614|OwnerPartId=1|FormalType=1|PinConglomerate=58|PinLength=20|Location.X=720|Location.Y=600|Name=VCC|Designator=34|SwapIDPart=Ž&Ž||PinPropagationDelay=0.000000E+000
|RECORD=2|OwnerIndex=614|OwnerPartId=1|FormalType=1|PinConglomerate=58|PinLength=20|Location.X=720|Location.Y=610|Name=VCC|Designator=33|SwapIDPart=Ž&Ž||PinPropagationDelay=0.000000E+000
|RECORD=2|OwnerIndex=614|OwnerPartId=1|FormalType=1|PinConglomerate=58|PinLength=20|Location.X=720|Location.Y=570|Name=V_BCKP|Designator=36|SwapIDPart=Ž&Ž||PinPropagationDelay=0.000000E+000
|RECORD=2|OwnerIndex=614|OwnerPartId=1|FormalType=1|PinConglomerate=58|PinLength=20|Location.X=720|Location.Y=550|Name=V_USB|Designator=38|SwapIDPart=Ž&Ž||PinPropagationDelay=0.000000E+000
|RECORD=2|OwnerIndex=614|OwnerPartId=1|FormalType=1|PinConglomerate=58|PinLength=20|Location.X=720|Location.Y=590|Name=RESET_N|Designator=49|SwapIDPart=Ž&Ž||PinPropagationDelay=0.000000E+000
|RECORD=2|OwnerIndex=614|OwnerPartId=1|FormalType=1|PinConglomerate=58|PinLength=20|Location.X=720|Location.Y=530|Name=SAFEBOOT_N|Designator=50|SwapIDPart=Ž&Ž||PinPropagationDelay=0.000000E+000
|RECORD=2|OwnerIndex=614|OwnerPartId=1|FormalType=1|Electrical=4|PinConglomerate=56|PinLength=20|Location.X=840|Location.Y=580|Name=GND|Designator=14|SwapIDPart=Ž&Ž||PinPropagationDelay=0.000000E+000
|RECORD=2|OwnerIndex=614|OwnerPartId=1|FormalType=1|Electrical=4|PinConglomerate=56|PinLength=20|Location.X=840|Location.Y=610|Name=GND|Designator=1|SwapIDPart=Ž&Ž||PinPropagationDelay=0.000000E+000
|RECORD=2|OwnerIndex=614|OwnerPartId=1|FormalType=1|Electrical=4|PinConglomerate=56|PinLength=20|Location.X=840|Location.Y=600|Name=GND|Designator=3|SwapIDPart=Ž&Ž||PinPropagationDelay=0.000000E+000
|RECORD=2|OwnerIndex=614|OwnerPartId=1|FormalType=1|Electrical=4|PinConglomerate=56|PinLength=20|Location.X=840|Location.Y=590|Name=GND|Designator=12|SwapIDPart=Ž&Ž||PinPropagationDelay=0.000000E+000
|RECORD=2|OwnerIndex=614|OwnerPartId=1|FormalType=1|Electrical=4|PinConglomerate=56|PinLength=20|Location.X=840|Location.Y=570|Name=GND|Designator=32|SwapIDPart=Ž&Ž||PinPropagationDelay=0.000000E+000
|RECORD=2|OwnerIndex=614|OwnerPartId=1|FormalType=1|Electrical=4|PinConglomerate=56|PinLength=20|Location.X=840|Location.Y=560|Name=GND|Designator=37|SwapIDPart=Ž&Ž||PinPropagationDelay=0.000000E+000
|RECORD=2|OwnerIndex=614|OwnerPartId=1|FormalType=1|Electrical=4|PinConglomerate=56|PinLength=20|Location.X=840|Location.Y=550|Name=GND|Designator=41|SwapIDPart=Ž&Ž||PinPropagationDelay=0.000000E+000
|RECORD=2|OwnerIndex=614|OwnerPartId=1|FormalType=1|Electrical=4|PinConglomerate=56|PinLength=20|Location.X=840|Location.Y=540|Name=GND|Designator=48|SwapIDPart=Ž&Ž||PinPropagationDelay=0.000000E+000
|RECORD=2|OwnerIndex=614|OwnerPartId=1|FormalType=1|Electrical=4|PinConglomerate=56|PinLength=20|Location.X=840|Location.Y=530|Name=GND|Designator=55|SwapIDPart=Ž&Ž||PinPropagationDelay=0.000000E+000
|RECORD=34|OwnerIndex=614|IndexInSheet=-1|OwnerPartId=-1|Location.X=720|Location.Y=620|Color=8388608|FontID=1|Text=U1|Name=Designator|ReadOnlyState=1
|RECORD=41|OwnerIndex=614|IndexInSheet=-1|OwnerPartId=-1|Location.X=790|Location.Y=510|Color=8388608|FontID=1|Text=ZED-F9T-00B|Name=Comment
|RECORD=44|OwnerIndex=614
|RECORD=45|OwnerIndex=704|IndexInSheet=-1|UseComponentLibrary=T|ModelName=GPS_ZED-F9T|ModelType=PCBLIB|DatafileCount=1|ModelDatafileEntity0=GPS_ZED-F9T|ModelDatafileKind0=PCBLib|IsCurrent=T|DatalinksLocked=T|DatabaseDatalinksLocked=T|IntegratedModel=T|DatabaseModel=T
|RECORD=46|OwnerIndex=705
|RECORD=48|OwnerIndex=705
|RECORD=1|LibReference=GPS_ZED-F9T|ComponentDescription=Multi-band GNSS Receiver with Nanosecond-level Timing Accuracy|PartCount=4|DisplayModeCount=1|IndexInSheet=58|OwnerPartId=-1|Location.X=720|Location.Y=230|CurrentPartId=2|LibraryPath=*|SourceLibraryName=GNSS_Receiver_Library.IntLib|TargetFileName=*|AreaColor=11599871|Color=128|PartIDLocked=F|DesignItemId=GPS_ZED-F9T|AllPinCount=34
|RECORD=41|OwnerIndex=708|OwnerPartId=-1|Location.X=698|Location.Y=245|Color=8388608|FontID=1|IsHidden=T|Text=Digi-Key|Name=Supplier 1|ReadOnlyState=3
|RECORD=41|OwnerIndex=708|IndexInSheet=1|OwnerPartId=-1|Location.X=698|Location.Y=255|Color=8388608|FontID=1|IsHidden=T|Text=u-blox|Name=Manufacturer
|RECORD=41|OwnerIndex=708|IndexInSheet=2|OwnerPartId=-1|Location.X=698|Location.Y=255|Color=8388608|FontID=1|IsHidden=T|Text=ZED-F9T-00B|Name=Manufacturer Part Number
|RECORD=41|OwnerIndex=708|IndexInSheet=3|OwnerPartId=-1|Location.X=698|Location.Y=255|Color=8388608|FontID=1|IsHidden=T|Text=Yes|Name=RoHS
|RECORD=41|OwnerIndex=708|IndexInSheet=4|OwnerPartId=-1|Location.X=698|Location.Y=255|Color=8388608|FontID=1|IsHidden=T|Text=RF Receivers, Transceivers|Name=Category
|RECORD=41|OwnerIndex=708|IndexInSheet=5|OwnerPartId=-1|Location.X=698|Location.Y=255|Color=8388608|FontID=1|IsHidden=T|Text=826|Name=Stock 1|ReadOnlyState=3
|RECORD=41|OwnerIndex=708|IndexInSheet=6|OwnerPartId=-1|Location.X=698|Location.Y=255|Color=8388608|FontID=1|IsHidden=T|Text=1=199.00000, 10=198.80000, 50=180.89020 (USD)|Name=Pricing 1|ReadOnlyState=3
|RECORD=41|OwnerIndex=708|IndexInSheet=7|OwnerPartId=-1|Location.X=698|Location.Y=255|Color=8388608|FontID=1|IsHidden=T|Text=SMD/SMT|Name=Case/Package
|RECORD=41|OwnerIndex=708|IndexInSheet=8|OwnerPartId=-1|Location.X=698|Location.Y=255|Color=8388608|FontID=1|IsHidden=T|Text=-40°C|Name=Min Operating Temperature
|RECORD=41|OwnerIndex=708|IndexInSheet=9|OwnerPartId=-1|Location.X=698|Location.Y=255|Color=8388608|FontID=1|IsHidden=T|Text=85°C|Name=Max Operating Temperature
|RECORD=41|OwnerIndex=708|IndexInSheet=10|OwnerPartId=-1|Location.X=698|Location.Y=255|Color=8388608|FontID=1|IsHidden=T|Text=I2C,SPI,USB,UART|Name=Interface
|RECORD=41|OwnerIndex=708|IndexInSheet=11|OwnerPartId=-1|Location.X=698|Location.Y=255|Color=8388608|FontID=1|IsHidden=T|Text=Tape and Reel|Name=Packaging
|RECORD=41|OwnerIndex=708|IndexInSheet=12|OwnerPartId=-1|Location.X=698|Location.Y=255|Color=8388608|FontID=1|IsHidden=T|Text=-166dBm|Name=Sensitivity
|RECORD=41|OwnerIndex=708|IndexInSheet=13|OwnerPartId=-1|Location.X=698|Location.Y=255|Color=8388608|FontID=2|IsHidden=T|Text=https://www.u-blox.com/sites/default/files/ZED-F9T_ProductSummary_%28UBX-18011626%29.pdf?src-supplier=Digi-Key|Name=ComponentLink1URL
|RECORD=41|OwnerIndex=708|IndexInSheet=14|OwnerPartId=-1|Location.X=698|Location.Y=255|Color=8388608|FontID=2|IsHidden=T|Text=https://www.u-blox.com/sites/default/files/ZED-F9T_ProductSummary_%28UBX-18011626%29.pdf?src-supplier=Digi-Key|Name=ComponentLink1Description
|RECORD=41|OwnerIndex=708|IndexInSheet=15|OwnerPartId=-1|Location.X=720|Location.Y=230|Color=8388608|FontID=1|IsHidden=T|Text=672-1197-1-ND|Name=Supplier Part Number 1|ReadOnlyState=3
|RECORD=14|OwnerIndex=708|IsNotAccesible=T|IndexInSheet=16|OwnerPartId=2|Location.X=720|Location.Y=140|Corner.X=810|Corner.Y=230|Color=128|AreaColor=11599871|IsSolid=T
|RECORD=2|OwnerIndex=708|OwnerPartId=2|FormalType=1|Electrical=2|PinConglomerate=56|PinLength=20|Location.X=810|Location.Y=220|Name=VCC_RF|Designator=7|SwapIDPart=Ž&Ž||PinPropagationDelay=0.000000E+000
|RECORD=2|OwnerIndex=708|OwnerPartId=2|FormalType=1|PinConglomerate=58|PinLength=20|Location.X=720|Location.Y=220|Name=RF_IN|Designator=2|SwapIDPart=Ž&Ž||PinPropagationDelay=0.000000E+000
|RECORD=2|OwnerIndex=708|OwnerPartId=2|FormalType=1|PinConglomerate=58|PinLength=20|Location.X=720|Location.Y=190|Name=ANT_DETECT|Designator=4|SwapIDPart=Ž&Ž||PinPropagationDelay=0.000000E+000
|RECORD=2|OwnerIndex=708|OwnerPartId=2|FormalType=1|Electrical=2|PinConglomerate=58|PinLength=20|Location.X=720|Location.Y=180|Name=ANT_OFF|Designator=5|SwapIDPart=Ž&Ž||PinPropagationDelay=0.000000E+000
|RECORD=2|OwnerIndex=708|OwnerPartId=2|FormalType=1|PinConglomerate=58|PinLength=20|Location.X=720|Location.Y=170|Name=ANT_SHORT_N|Designator=6|SwapIDPart=Ž&Ž||PinPropagationDelay=0.000000E+000
|RECORD=2|OwnerIndex=708|OwnerPartId=2|FormalType=1|Electrical=2|PinConglomerate=56|PinLength=20|Location.X=810|Location.Y=150|Name=GEOFENCE_STAT|Designator=19|SwapIDPart=Ž&Ž||PinPropagationDelay=0.000000E+000
|RECORD=14|OwnerIndex=708|IsNotAccesible=T|IndexInSheet=23|OwnerPartId=3|Location.X=720|Location.Y=70|Corner.X=830|Corner.Y=230|Color=128|AreaColor=11599871|IsSolid=T
|RECORD=2|OwnerIndex=708|OwnerPartId=3|FormalType=1|PinConglomerate=58|PinLength=20|Location.X=720|Location.Y=220|Name=D_SEL|Designator=47|SwapIDPart=Ž&Ž||PinPropagationDelay=0.000000E+000
|RECORD=2|OwnerIndex=708|OwnerPartId=3|FormalType=1|Electrical=2|PinConglomerate=56|PinLength=20|Location.X=830|Location.Y=220|Name=TIMEPULSE|Designator=53|SwapIDPart=Ž&Ž||PinPropagationDelay=0.000000E+000
|RECORD=2|OwnerIndex=708|OwnerPartId=3|FormalType=1|Electrical=2|PinConglomerate=56|PinLength=20|Location.X=830|Location.Y=210|Name=TIMEPULSE2|Designator=54|SwapIDPart=Ž&Ž||PinPropagationDelay=0.000000E+000
|RECORD=2|OwnerIndex=708|OwnerPartId=3|FormalType=1|PinConglomerate=58|PinLength=20|Location.X=720|Location.Y=110|Name=RXD2|Designator=26|SwapIDPart=Ž&Ž||PinPropagationDelay=0.000000E+000
|RECORD=2|OwnerIndex=708|OwnerPartId=3|FormalType=1|Electrical=2|PinConglomerate=58|PinLength=20|Location.X=720|Location.Y=120|Name=TXD2|Designator=27|SwapIDPart=Ž&Ž||PinPropagationDelay=0.000000E+000
|RECORD=2|OwnerIndex=708|OwnerPartId=3|FormalType=1|Electrical=1|PinConglomerate=58|PinLength=20|Location.X=720|Location.Y=90|Name=USB_DM|Designator=39|SwapIDPart=Ž&Ž||PinPropagationDelay=0.000000E+000
|RECORD=2|OwnerIndex=708|OwnerPartId=3|FormalType=1|Electrical=1|PinConglomerate=58|PinLength=20|Location.X=720|Location.Y=80|Name=USB_DP|Designator=40|SwapIDPart=Ž&Ž||PinPropagationDelay=0.000000E+000
|RECORD=2|OwnerIndex=708|OwnerPartId=3|FormalType=1|Electrical=2|PinConglomerate=58|PinLength=20|Location.X=720|Location.Y=170|Name=TXD/SPI_MISO|Designator=42|SwapIDPart=Ž&Ž||PinPropagationDelay=0.000000E+000
|RECORD=2|OwnerIndex=708|OwnerPartId=3|FormalType=1|PinConglomerate=58|PinLength=20|Location.X=720|Location.Y=160|Name=RXD/SPI_MOSI|Designator=43|SwapIDPart=Ž&Ž||PinPropagationDelay=0.000000E+000
|RECORD=2|OwnerIndex=708|OwnerPartId=3|FormalType=1|Electrical=1|PinConglomerate=58|PinLength=20|Location.X=720|Location.Y=150|Name=SDA/SPI_CS_N|Designator=44|SwapIDPart=Ž&Ž||PinPropagationDelay=0.000000E+000
|RECORD=2|OwnerIndex=708|OwnerPartId=3|FormalType=1|Electrical=1|PinConglomerate=58|PinLength=20|Location.X=720|Location.Y=140|Name=SCL/SPI_CLK|Designator=45|SwapIDPart=Ž&Ž||PinPropagationDelay=0.000000E+000
|RECORD=2|OwnerIndex=708|OwnerPartId=3|FormalType=1|PinConglomerate=58|PinLength=20|Location.X=720|Location.Y=200|Name=EXTIN|Designator=51|SwapIDPart=Ž&Ž||PinPropagationDelay=0.000000E+000
|RECORD=2|OwnerIndex=708|OwnerPartId=3|FormalType=1|PinConglomerate=58|PinLength=20|Location.X=720|Location.Y=190|Name=EXTIN2|Designator=52|SwapIDPart=Ž&Ž||PinPropagationDelay=0.000000E+000
|RECORD=14|OwnerIndex=708|IsNotAccesible=T|IndexInSheet=37|OwnerPartId=1|Location.X=720|Location.Y=130|Corner.X=840|Corner.Y=230|Color=128|AreaColor=11599871|IsSolid=T
|RECORD=2|OwnerIndex=708|OwnerPartId=1|FormalType=1|PinConglomerate=58|PinLength=20|Location.X=720|Location.Y=210|Name=VCC|Designator=34|SwapIDPart=Ž&Ž||PinPropagationDelay=0.000000E+000
|RECORD=2|OwnerIndex=708|OwnerPartId=1|FormalType=1|PinConglomerate=58|PinLength=20|Location.X=720|Location.Y=220|Name=VCC|Designator=33|SwapIDPart=Ž&Ž||PinPropagationDelay=0.000000E+000
|RECORD=2|OwnerIndex=708|OwnerPartId=1|FormalType=1|PinConglomerate=58|PinLength=20|Location.X=720|Location.Y=180|Name=V_BCKP|Designator=36|SwapIDPart=Ž&Ž||PinPropagationDelay=0.000000E+000
|RECORD=2|OwnerIndex=708|OwnerPartId=1|FormalType=1|PinConglomerate=58|PinLength=20|Location.X=720|Location.Y=160|Name=V_USB|Designator=38|SwapIDPart=Ž&Ž||PinPropagationDelay=0.000000E+000
|RECORD=2|OwnerIndex=708|OwnerPartId=1|FormalType=1|PinConglomerate=58|PinLength=20|Location.X=720|Location.Y=200|Name=RESET_N|Designator=49|SwapIDPart=Ž&Ž||PinPropagationDelay=0.000000E+000
|RECORD=2|OwnerIndex=708|OwnerPartId=1|FormalType=1|PinConglomerate=58|PinLength=20|Location.X=720|Location.Y=140|Name=SAFEBOOT_N|Designator=50|SwapIDPart=Ž&Ž||PinPropagationDelay=0.000000E+000
|RECORD=2|OwnerIndex=708|OwnerPartId=1|FormalType=1|Electrical=4|PinConglomerate=56|PinLength=20|Location.X=840|Location.Y=190|Name=GND|Designator=14|SwapIDPart=Ž&Ž||PinPropagationDelay=0.000000E+000
|RECORD=2|OwnerIndex=708|OwnerPartId=1|FormalType=1|Electrical=4|PinConglomerate=56|PinLength=20|Location.X=840|Location.Y=220|Name=GND|Designator=1|SwapIDPart=Ž&Ž||PinPropagationDelay=0.000000E+000
|RECORD=2|OwnerIndex=708|OwnerPartId=1|FormalType=1|Electrical=4|PinConglomerate=56|PinLength=20|Location.X=840|Location.Y=210|Name=GND|Designator=3|SwapIDPart=Ž&Ž||PinPropagationDelay=0.000000E+000
|RECORD=2|OwnerIndex=708|OwnerPartId=1|FormalType=1|Electrical=4|PinConglomerate=56|PinLength=20|Location.X=840|Location.Y=200|Name=GND|Designator=12|SwapIDPart=Ž&Ž||PinPropagationDelay=0.000000E+000
|RECORD=2|OwnerIndex=708|OwnerPartId=1|FormalType=1|Electrical=4|PinConglomerate=56|PinLength=20|Location.X=840|Location.Y=180|Name=GND|Designator=32|SwapIDPart=Ž&Ž||PinPropagationDelay=0.000000E+000
|RECORD=2|OwnerIndex=708|OwnerPartId=1|FormalType=1|Electrical=4|PinConglomerate=56|PinLength=20|Location.X=840|Location.Y=170|Name=GND|Designator=37|SwapIDPart=Ž&Ž||PinPropagationDelay=0.000000E+000
|RECORD=2|OwnerIndex=708|OwnerPartId=1|FormalType=1|Electrical=4|PinConglomerate=56|PinLength=20|Location.X=840|Location.Y=160|Name=GND|Designator=41|SwapIDPart=Ž&Ž||PinPropagationDelay=0.000000E+000
|RECORD=2|OwnerIndex=708|OwnerPartId=1|FormalType=1|Electrical=4|PinConglomerate=56|PinLength=20|Location.X=840|Location.Y=150|Name=GND|Designator=48|SwapIDPart=Ž&Ž||PinPropagationDelay=0.000000E+000
|RECORD=2|OwnerIndex=708|OwnerPartId=1|FormalType=1|Electrical=4|PinConglomerate=56|PinLength=20|Location.X=840|Location.Y=140|Name=GND|Designator=55|SwapIDPart=Ž&Ž||PinPropagationDelay=0.000000E+000
|RECORD=34|OwnerIndex=708|IndexInSheet=-1|OwnerPartId=-1|Location.X=720|Location.Y=230|Color=8388608|FontID=1|Text=U1|Name=Designator|ReadOnlyState=1
|RECORD=41|OwnerIndex=708|IndexInSheet=-1|OwnerPartId=-1|Location.X=760|Location.Y=130|Color=8388608|FontID=1|Text=ZED-F9T-00B|Name=Comment
|RECORD=44|OwnerIndex=708
|RECORD=45|OwnerIndex=798|IndexInSheet=-1|UseComponentLibrary=T|ModelName=GPS_ZED-F9T|ModelType=PCBLIB|DatafileCount=1|ModelDatafileEntity0=GPS_ZED-F9T|ModelDatafileKind0=PCBLib|IsCurrent=T|DatalinksLocked=T|DatabaseDatalinksLocked=T|IntegratedModel=T|DatabaseModel=T
|RECORD=46|OwnerIndex=799
|RECORD=48|OwnerIndex=799
|RECORD=1|LibReference=GPS_ZED-F9T|ComponentDescription=Multi-band GNSS Receiver with Nanosecond-level Timing Accuracy|PartCount=4|DisplayModeCount=1|IndexInSheet=59|OwnerPartId=-1|Location.X=720|Location.Y=440|CurrentPartId=3|LibraryPath=*|SourceLibraryName=GNSS_Receiver_Library.IntLib|TargetFileName=*|AreaColor=11599871|Color=128|PartIDLocked=F|DesignItemId=GPS_ZED-F9T|AllPinCount=34
|RECORD=41|OwnerIndex=802|OwnerPartId=-1|Location.X=698|Location.Y=455|Color=8388608|FontID=1|IsHidden=T|Text=Digi-Key|Name=Supplier 1|ReadOnlyState=3
|RECORD=41|OwnerIndex=802|IndexInSheet=1|OwnerPartId=-1|Location.X=698|Location.Y=465|Color=8388608|FontID=1|IsHidden=T|Text=u-blox|Name=Manufacturer
|RECORD=41|OwnerIndex=802|IndexInSheet=2|OwnerPartId=-1|Location.X=698|Location.Y=465|Color=8388608|FontID=1|IsHidden=T|Text=ZED-F9T-00B|Name=Manufacturer Part Number
|RECORD=41|OwnerIndex=802|IndexInSheet=3|OwnerPartId=-1|Location.X=698|Location.Y=465|Color=8388608|FontID=1|IsHidden=T|Text=Yes|Name=RoHS
|RECORD=41|OwnerIndex=802|IndexInSheet=4|OwnerPartId=-1|Location.X=698|Location.Y=465|Color=8388608|FontID=1|IsHidden=T|Text=RF Receivers, Transceivers|Name=Category
|RECORD=41|OwnerIndex=802|IndexInSheet=5|OwnerPartId=-1|Location.X=698|Location.Y=465|Color=8388608|FontID=1|IsHidden=T|Text=826|Name=Stock 1|ReadOnlyState=3
|RECORD=41|OwnerIndex=802|IndexInSheet=6|OwnerPartId=-1|Location.X=698|Location.Y=465|Color=8388608|FontID=1|IsHidden=T|Text=1=199.00000, 10=198.80000, 50=180.89020 (USD)|Name=Pricing 1|ReadOnlyState=3
|RECORD=41|OwnerIndex=802|IndexInSheet=7|OwnerPartId=-1|Location.X=698|Location.Y=465|Color=8388608|FontID=1|IsHidden=T|Text=SMD/SMT|Name=Case/Package
|RECORD=41|OwnerIndex=802|IndexInSheet=8|OwnerPartId=-1|Location.X=698|Location.Y=465|Color=8388608|FontID=1|IsHidden=T|Text=-40°C|Name=Min Operating Temperature
|RECORD=41|OwnerIndex=802|IndexInSheet=9|OwnerPartId=-1|Location.X=698|Location.Y=465|Color=8388608|FontID=1|IsHidden=T|Text=85°C|Name=Max Operating Temperature
|RECORD=41|OwnerIndex=802|IndexInSheet=10|OwnerPartId=-1|Location.X=698|Location.Y=465|Color=8388608|FontID=1|IsHidden=T|Text=I2C,SPI,USB,UART|Name=Interface
|RECORD=41|OwnerIndex=802|IndexInSheet=11|OwnerPartId=-1|Location.X=698|Location.Y=465|Color=8388608|FontID=1|IsHidden=T|Text=Tape and Reel|Name=Packaging
|RECORD=41|OwnerIndex=802|IndexInSheet=12|OwnerPartId=-1|Location.X=698|Location.Y=465|Color=8388608|FontID=1|IsHidden=T|Text=-166dBm|Name=Sensitivity
|RECORD=41|OwnerIndex=802|IndexInSheet=13|OwnerPartId=-1|Location.X=698|Location.Y=465|Color=8388608|FontID=2|IsHidden=T|Text=https://www.u-blox.com/sites/default/files/ZED-F9T_ProductSummary_%28UBX-18011626%29.pdf?src-supplier=Digi-Key|Name=ComponentLink1URL
|RECORD=41|OwnerIndex=802|IndexInSheet=14|OwnerPartId=-1|Location.X=698|Location.Y=465|Color=8388608|FontID=2|IsHidden=T|Text=https://www.u-blox.com/sites/default/files/ZED-F9T_ProductSummary_%28UBX-18011626%29.pdf?src-supplier=Digi-Key|Name=ComponentLink1Description
|RECORD=41|OwnerIndex=802|IndexInSheet=15|OwnerPartId=-1|Location.X=720|Location.Y=440|Color=8388608|FontID=1|IsHidden=T|Text=672-1197-1-ND|Name=Supplier Part Number 1|ReadOnlyState=3
|RECORD=14|OwnerIndex=802|IsNotAccesible=T|IndexInSheet=16|OwnerPartId=2|Location.X=720|Location.Y=350|Corner.X=810|Corner.Y=440|Color=128|AreaColor=11599871|IsSolid=T
|RECORD=2|OwnerIndex=802|OwnerPartId=2|FormalType=1|Electrical=2|PinConglomerate=56|PinLength=20|Location.X=810|Location.Y=430|Name=VCC_RF|Designator=7|SwapIDPart=Ž&Ž||PinPropagationDelay=0.000000E+000
|RECORD=2|OwnerIndex=802|OwnerPartId=2|FormalType=1|PinConglomerate=58|PinLength=20|Location.X=720|Location.Y=430|Name=RF_IN|Designator=2|SwapIDPart=Ž&Ž||PinPropagationDelay=0.000000E+000
|RECORD=2|OwnerIndex=802|OwnerPartId=2|FormalType=1|PinConglomerate=58|PinLength=20|Location.X=720|Location.Y=400|Name=ANT_DETECT|Designator=4|SwapIDPart=Ž&Ž||PinPropagationDelay=0.000000E+000
|RECORD=2|OwnerIndex=802|OwnerPartId=2|FormalType=1|Electrical=2|PinConglomerate=58|PinLength=20|Location.X=720|Location.Y=390|Name=ANT_OFF|Designator=5|SwapIDPart=Ž&Ž||PinPropagationDelay=0.000000E+000
|RECORD=2|OwnerIndex=802|OwnerPartId=2|FormalType=1|PinConglomerate=58|PinLength=20|Location.X=720|Location.Y=380|Name=ANT_SHORT_N|Designator=6|SwapIDPart=Ž&Ž||PinPropagationDelay=0.000000E+000
|RECORD=2|OwnerIndex=802|OwnerPartId=2|FormalType=1|Electrical=2|PinConglomerate=56|PinLength=20|Location.X=810|Location.Y=360|Name=GEOFENCE_STAT|Designator=19|SwapIDPart=Ž&Ž||PinPropagationDelay=0.000000E+000
|RECORD=14|OwnerIndex=802|IsNotAccesible=T|IndexInSheet=23|OwnerPartId=3|Location.X=720|Location.Y=280|Corner.X=830|Corner.Y=440|Color=128|AreaColor=11599871|IsSolid=T
|RECORD=2|OwnerIndex=802|OwnerPartId=3|FormalType=1|PinConglomerate=58|PinLength=20|Location.X=720|Location.Y=430|Name=D_SEL|Designator=47|SwapIDPart=Ž&Ž||PinPropagationDelay=0.000000E+000
|RECORD=2|OwnerIndex=802|OwnerPartId=3|FormalType=1|Electrical=2|PinConglomerate=56|PinLength=20|Location.X=830|Location.Y=430|Name=TIMEPULSE|Designator=53|SwapIDPart=Ž&Ž||PinPropagationDelay=0.000000E+000
|RECORD=2|OwnerIndex=802|OwnerPartId=3|FormalType=1|Electrical=2|PinConglomerate=56|PinLength=20|Location.X=830|Location.Y=420|Name=TIMEPULSE2|Designator=54|SwapIDPart=Ž&Ž||PinPropagationDelay=0.000000E+000
|RECORD=2|OwnerIndex=802|OwnerPartId=3|FormalType=1|PinConglomerate=58|PinLength=20|Location.X=720|Location.Y=320|Name=RXD2|Designator=26|SwapIDPart=Ž&Ž||PinPropagationDelay=0.000000E+000
|RECORD=2|OwnerIndex=802|OwnerPartId=3|FormalType=1|Electrical=2|PinConglomerate=58|PinLength=20|Location.X=720|Location.Y=330|Name=TXD2|Designator=27|SwapIDPart=Ž&Ž||PinPropagationDelay=0.000000E+000
|RECORD=2|OwnerIndex=802|OwnerPartId=3|FormalType=1|Electrical=1|PinConglomerate=58|PinLength=20|Location.X=720|Location.Y=300|Name=USB_DM|Designator=39|SwapIDPart=Ž&Ž||PinPropagationDelay=0.000000E+000
|RECORD=2|OwnerIndex=802|OwnerPartId=3|FormalType=1|Electrical=1|PinConglomerate=58|PinLength=20|Location.X=720|Location.Y=290|Name=USB_DP|Designator=40|SwapIDPart=Ž&Ž||PinPropagationDelay=0.000000E+000
|RECORD=2|OwnerIndex=802|OwnerPartId=3|FormalType=1|Electrical=2|PinConglomerate=58|PinLength=20|Location.X=720|Location.Y=380|Name=TXD/SPI_MISO|Designator=42|SwapIDPart=Ž&Ž||PinPropagationDelay=0.000000E+000
|RECORD=2|OwnerIndex=802|OwnerPartId=3|FormalType=1|PinConglomerate=58|PinLength=20|Location.X=720|Location.Y=370|Name=RXD/SPI_MOSI|Designator=43|SwapIDPart=Ž&Ž||PinPropagationDelay=0.000000E+000
|RECORD=2|OwnerIndex=802|OwnerPartId=3|FormalType=1|Electrical=1|PinConglomerate=58|PinLength=20|Location.X=720|Location.Y=360|Name=SDA/SPI_CS_N|Designator=44|SwapIDPart=Ž&Ž||PinPropagationDelay=0.000000E+000
|RECORD=2|OwnerIndex=802|OwnerPartId=3|FormalType=1|Electrical=1|PinConglomerate=58|PinLength=20|Location.X=720|Location.Y=350|Name=SCL/SPI_CLK|Designator=45|SwapIDPart=Ž&Ž||PinPropagationDelay=0.000000E+000
|RECORD=2|OwnerIndex=802|OwnerPartId=3|FormalType=1|PinConglomerate=58|PinLength=20|Location.X=720|Location.Y=410|Name=EXTIN|Designator=51|SwapIDPart=Ž&Ž||PinPropagationDelay=0.000000E+000
|RECORD=2|OwnerIndex=802|OwnerPartId=3|FormalType=1|PinConglomerate=58|PinLength=20|Location.X=720|Location.Y=400|Name=EXTIN2|Designator=52|SwapIDPart=Ž&Ž||PinPropagationDelay=0.000000E+000
|RECORD=14|OwnerIndex=802|IsNotAccesible=T|IndexInSheet=37|OwnerPartId=1|Location.X=720|Location.Y=340|Corner.X=840|Corner.Y=440|Color=128|AreaColor=11599871|IsSolid=T
|RECORD=2|OwnerIndex=802|OwnerPartId=1|FormalType=1|PinConglomerate=58|PinLength=20|Location.X=720|Location.Y=420|Name=VCC|Designator=34|SwapIDPart=Ž&Ž||PinPropagationDelay=0.000000E+000
|RECORD=2|OwnerIndex=802|OwnerPartId=1|FormalType=1|PinConglomerate=58|PinLength=20|Location.X=720|Location.Y=430|Name=VCC|Designator=33|SwapIDPart=Ž&Ž||PinPropagationDelay=0.000000E+000
|RECORD=2|OwnerIndex=802|OwnerPartId=1|FormalType=1|PinConglomerate=58|PinLength=20|Location.X=720|Location.Y=390|Name=V_BCKP|Designator=36|SwapIDPart=Ž&Ž||PinPropagationDelay=0.000000E+000
|RECORD=2|OwnerIndex=802|OwnerPartId=1|FormalType=1|PinConglomerate=58|PinLength=20|Location.X=720|Location.Y=370|Name=V_USB|Designator=38|SwapIDPart=Ž&Ž||PinPropagationDelay=0.000000E+000
|RECORD=2|OwnerIndex=802|OwnerPartId=1|FormalType=1|PinConglomerate=58|PinLength=20|Location.X=720|Location.Y=410|Name=RESET_N|Designator=49|SwapIDPart=Ž&Ž||PinPropagationDelay=0.000000E+000
|RECORD=2|OwnerIndex=802|OwnerPartId=1|FormalType=1|PinConglomerate=58|PinLength=20|Location.X=720|Location.Y=350|Name=SAFEBOOT_N|Designator=50|SwapIDPart=Ž&Ž||PinPropagationDelay=0.000000E+000
|RECORD=2|OwnerIndex=802|OwnerPartId=1|FormalType=1|Electrical=4|PinConglomerate=56|PinLength=20|Location.X=840|Location.Y=400|Name=GND|Designator=14|SwapIDPart=Ž&Ž||PinPropagationDelay=0.000000E+000
|RECORD=2|OwnerIndex=802|OwnerPartId=1|FormalType=1|Electrical=4|PinConglomerate=56|PinLength=20|Location.X=840|Location.Y=430|Name=GND|Designator=1|SwapIDPart=Ž&Ž||PinPropagationDelay=0.000000E+000
|RECORD=2|OwnerIndex=802|OwnerPartId=1|FormalType=1|Electrical=4|PinConglomerate=56|PinLength=20|Location.X=840|Location.Y=420|Name=GND|Designator=3|SwapIDPart=Ž&Ž||PinPropagationDelay=0.000000E+000
|RECORD=2|OwnerIndex=802|OwnerPartId=1|FormalType=1|Electrical=4|PinConglomerate=56|PinLength=20|Location.X=840|Location.Y=410|Name=GND|Designator=12|SwapIDPart=Ž&Ž||PinPropagationDelay=0.000000E+000
|RECORD=2|OwnerIndex=802|OwnerPartId=1|FormalType=1|Electrical=4|PinConglomerate=56|PinLength=20|Location.X=840|Location.Y=390|Name=GND|Designator=32|SwapIDPart=Ž&Ž||PinPropagationDelay=0.000000E+000
|RECORD=2|OwnerIndex=802|OwnerPartId=1|FormalType=1|Electrical=4|PinConglomerate=56|PinLength=20|Location.X=840|Location.Y=380|Name=GND|Designator=37|SwapIDPart=Ž&Ž||PinPropagationDelay=0.000000E+000
|RECORD=2|OwnerIndex=802|OwnerPartId=1|FormalType=1|Electrical=4|PinConglomerate=56|PinLength=20|Location.X=840|Location.Y=370|Name=GND|Designator=41|SwapIDPart=Ž&Ž||PinPropagationDelay=0.000000E+000
|RECORD=2|OwnerIndex=802|OwnerPartId=1|FormalType=1|Electrical=4|PinConglomerate=56|PinLength=20|Location.X=840|Location.Y=360|Name=GND|Designator=48|SwapIDPart=Ž&Ž||PinPropagationDelay=0.000000E+000
|RECORD=2|OwnerIndex=802|OwnerPartId=1|FormalType=1|Electrical=4|PinConglomerate=56|PinLength=20|Location.X=840|Location.Y=350|Name=GND|Designator=55|SwapIDPart=Ž&Ž||PinPropagationDelay=0.000000E+000
|RECORD=34|OwnerIndex=802|IndexInSheet=-1|OwnerPartId=-1|Location.X=720|Location.Y=440|Color=8388608|FontID=1|Text=U1|Name=Designator|ReadOnlyState=1
|RECORD=41|OwnerIndex=802|IndexInSheet=-1|OwnerPartId=-1|Location.X=780|Location.Y=270|Color=8388608|FontID=1|Text=ZED-F9T-00B|Name=Comment
|RECORD=44|OwnerIndex=802
|RECORD=45|OwnerIndex=892|IndexInSheet=-1|UseComponentLibrary=T|ModelName=GPS_ZED-F9T|ModelType=PCBLIB|DatafileCount=1|ModelDatafileEntity0=GPS_ZED-F9T|ModelDatafileKind0=PCBLib|IsCurrent=T|DatalinksLocked=T|DatabaseDatalinksLocked=T|IntegratedModel=T|DatabaseModel=T
|RECORD=46|OwnerIndex=893
|RECORD=48|OwnerIndex=893
|RECORD=17|IndexInSheet=60|OwnerPartId=-1|Style=2|ShowNetName=T|Location.X=600|Location.Y=660|Orientation=1|Color=128|FontID=1|Text=VCC
|RECORD=25|IndexInSheet=61|OwnerPartId=-1|Location.X=670|Location.Y=590|Color=128|FontID=1|Text=RST
|RECORD=1|LibReference=Capacitor_300mil|ComponentDescription=CAP, CER, X5R, 1UF, 10%, 25V, 0402, 0.55MM T|PartCount=2|DisplayModeCount=1|IndexInSheet=62|OwnerPartId=-1|Location.X=650|Location.Y=660|CurrentPartId=1|LibraryPath=*|SourceLibraryName=RL Research Altium Server|TargetFileName=*|AreaColor=11599871|Color=128|PartIDLocked=T|DesignItemId=CAP-CMP-00365-3|AllPinCount=2
|RECORD=13|OwnerIndex=898|IsNotAccesible=T|OwnerPartId=1|Location.X=640|Location.Y=648|Corner.X=660|Corner.Y=648|LineWidth=1|Color=16711680
|RECORD=6|OwnerIndex=898|IsNotAccesible=T|IndexInSheet=1|OwnerPartId=1|LineWidth=1|Color=16711680|LocationCount=2|X1=640|Y1=642|X2=660|Y2=642
|RECORD=6|OwnerIndex=898|IsNotAccesible=T|IndexInSheet=2|OwnerPartId=1|LineWidth=1|Color=16711680|LocationCount=2|X1=650|Y1=640|X2=650|Y2=642
|RECORD=6|OwnerIndex=898|IsNotAccesible=T|IndexInSheet=3|OwnerPartId=1|LineWidth=1|Color=16711680|LocationCount=2|X1=650|Y1=650|X2=650|Y2=648
|RECORD=2|OwnerIndex=898|OwnerPartId=1|FormalType=1|Electrical=4|PinConglomerate=33|PinLength=10|Location.X=650|Location.Y=650|Name=1|Designator=1|SwapIDPart=0|PinName_PositionConglomerate=16|Name_CustomFontID=16|PinDesignator_PositionConglomerate=16|Designator_CustomFontID=16|PinPropagationDelay=0.000000E+000
|RECORD=2|OwnerIndex=898|OwnerPartId=1|FormalType=1|Electrical=4|PinConglomerate=35|PinLength=10|Location.X=650|Location.Y=640|Name=2|Designator=2|SwapIDPart=0|PinName_PositionConglomerate=16|Name_CustomFontID=16|PinDesignator_PositionConglomerate=16|Designator_CustomFontID=16|PinPropagationDelay=0.000000E+000
|RECORD=41|OwnerIndex=898|IndexInSheet=6|OwnerPartId=-1|Location.X=639|Location.Y=675|Color=8388608|FontID=2|IsHidden=T|Text=https://www.digikey.com/en/products/detail/murata-electronics/GRM155R61E105KA12D/4905139?s=N4IgTCBcDaIOICUCyBGArGhA2FBRFADGgNICCKYAIiALoC%2BQA|Name=Datasheet URL
|RECORD=41|OwnerIndex=898|IndexInSheet=7|OwnerPartId=-1|Location.X=639|Location.Y=675|Color=8388608|FontID=1|IsHidden=T|Text=Yes|Name=RoHS
|RECORD=41|OwnerIndex=898|IndexInSheet=8|OwnerPartId=-1|Location.X=639|Location.Y=675|Color=8388608|FontID=1|IsHidden=T|Text=Surface Mount, MLCC|Name=Mounting Type
|RECORD=41|OwnerIndex=898|IndexInSheet=9|OwnerPartId=-1|Location.X=639|Location.Y=675|Color=8388608|FontID=1|IsHidden=T|Name=Voltage - Rated
|RECORD=41|OwnerIndex=898|IndexInSheet=10|OwnerPartId=-1|Location.X=639|Location.Y=675|Color=8388608|FontID=1|IsHidden=T|Text=85°C|Name=Max Operating Temperature
|RECORD=41|OwnerIndex=898|IndexInSheet=11|OwnerPartId=-1|Location.X=639|Location.Y=675|Color=8388608|FontID=1|IsHidden=T|Text=Ceramic Capacitors|Name=Category
|RECORD=41|OwnerIndex=898|IndexInSheet=12|OwnerPartId=-1|Location.X=639|Location.Y=675|Color=8388608|FontID=1|IsHidden=T|Text=0.022" (0.55mm)|Name=Height
|RECORD=41|OwnerIndex=898|IndexInSheet=13|OwnerPartId=-1|Location.X=639|Location.Y=675|Color=8388608|FontID=1|IsHidden=T|Name=Ratings
|RECORD=41|OwnerIndex=898|IndexInSheet=14|OwnerPartId=-1|Location.X=639|Location.Y=675|Color=8388608|FontID=1|IsHidden=T|Name=Lead Spacing
|RECORD=41|OwnerIndex=898|IndexInSheet=15|OwnerPartId=-1|Location.X=661|Location.Y=641|Color=8388608|FontID=1|Name=Part Status
|RECORD=41|OwnerIndex=898|IndexInSheet=16|OwnerPartId=-1|Location.X=639|Location.Y=675|Color=8388608|FontID=1|IsHidden=T|Text=Digikey|Name=Supplier 1
|RECORD=41|OwnerIndex=898|IndexInSheet=17|OwnerPartId=-1|Location.X=639|Location.Y=675|Color=8388608|FontID=1|IsHidden=T|Name=Lead Style
|RECORD=41|OwnerIndex=898|IndexInSheet=18|OwnerPartId=-1|Location.X=639|Location.Y=675|Color=8388608|FontID=1|IsHidden=T|Text=GRM155R61E105KA12D|Name=Manufacturer Part Number
|RECORD=41|OwnerIndex=898|IndexInSheet=19|OwnerPartId=-1|Location.X=639|Location.Y=675|Color=8388608|FontID=1|IsHidden=T|Name=Features
|RECORD=41|OwnerIndex=898|IndexInSheet=20|OwnerPartId=-1|Location.X=661|Location.Y=631|Color=8388608|FontID=1|Text=±10%|Name=Tolerance
|RECORD=41|OwnerIndex=898|IndexInSheet=21|OwnerPartId=-1|Location.X=661|Location.Y=621|Color=8388608|FontID=1|Text=25V|Name=Voltage Rating
|RECORD=41|OwnerIndex=898|IndexInSheet=22|OwnerPartId=-1|Location.X=639|Location.Y=695|Color=8388608|FontID=1|IsHidden=T|Text=X5R|Name=Temperature Coefficient
|RECORD=41|OwnerIndex=898|IndexInSheet=23|OwnerPartId=-1|Location.X=639|Location.Y=695|Color=8388608|FontID=1|IsHidden=T|Name=Voltage Rating - AC
|RECORD=41|OwnerIndex=898|IndexInSheet=24|OwnerPartId=-1|Location.X=639|Location.Y=695|Color=8388608|FontID=1|IsHidden=T|Text=-55°C|Name=Min Operating Temperature
|RECORD=41|OwnerIndex=898|IndexInSheet=25|OwnerPartId=-1|Location.X=639|Location.Y=695|Color=8388608|FontID=1|IsHidden=T|Name=Type
|RECORD=41|OwnerIndex=898|IndexInSheet=26|OwnerPartId=-1|Location.X=639|Location.Y=695|Color=8388608|FontID=1|IsHidden=T|Text=0402 (1005 Metric)|Name=Case/Package
|RECORD=41|OwnerIndex=898|IndexInSheet=27|OwnerPartId=-1|Location.X=639|Location.Y=695|Color=8388608|FontID=1|IsHidden=T|Text=Non-polar|Name=Polarization
|RECORD=41|OwnerIndex=898|IndexInSheet=28|OwnerPartId=-1|Location.X=639|Location.Y=695|Color=8388608|FontID=1|IsHidden=T|Text=Murata|Name=Manufacturer
|RECORD=41|OwnerIndex=898|IndexInSheet=29|OwnerPartId=-1|Location.X=639|Location.Y=695|Color=8388608|FontID=1|IsHidden=T|Text=0.039" L x 0.020" W (1.00mm x 0.50mm)|Name=Size / Dimension
|RECORD=41|OwnerIndex=898|IndexInSheet=30|OwnerPartId=-1|Location.X=639|Location.Y=695|Color=8388608|FontID=1|IsHidden=T|Name=Impedance
|RECORD=41|OwnerIndex=898|IndexInSheet=31|OwnerPartId=-1|Location.X=639|Location.Y=695|Color=8388608|FontID=1|IsHidden=T|Text=825-00099-00|Name=Internal Part Number
|RECORD=41|OwnerIndex=898|IndexInSheet=32|OwnerPartId=-1|Location.X=639|Location.Y=695|Color=8388608|FontID=1|IsHidden=T|Text=Ceramic|Name=Composition
|RECORD=41|OwnerIndex=898|IndexInSheet=33|OwnerPartId=-1|Location.X=639|Location.Y=695|Color=8388608|FontID=1|IsHidden=T|Name=Thickness (Max)
|RECORD=41|OwnerIndex=898|IndexInSheet=34|OwnerPartId=-1|Location.X=639|Location.Y=695|Color=8388608|FontID=1|IsHidden=T|Text=490-10017-1-ND|Name=Supplier Part Number 1
|RECORD=41|OwnerIndex=898|IndexInSheet=35|OwnerPartId=-1|Location.X=639|Location.Y=695|Color=8388608|FontID=1|IsHidden=T|Name=ESR (Equivalent Series Resistance)
|RECORD=41|OwnerIndex=898|IndexInSheet=36|OwnerPartId=-1|Location.X=639|Location.Y=695|Color=8388608|FontID=1|IsHidden=T|Text=GRM155R61E|Name=Series
|RECORD=41|OwnerIndex=898|IndexInSheet=37|OwnerPartId=-1|Location.X=639|Location.Y=695|Color=8388608|FontID=1|IsHidden=T|Name=Failure Rate
|RECORD=41|OwnerIndex=898|IndexInSheet=38|OwnerPartId=-1|Location.X=639|Location.Y=695|Color=8388608|FontID=1|IsHidden=T|Text=General Purpose|Name=Applications
|RECORD=41|OwnerIndex=898|IndexInSheet=39|OwnerPartId=-1|Location.X=661|Location.Y=611|Color=8388608|FontID=1|Text=1µF|Name=Capacitance
|RECORD=41|OwnerIndex=898|IndexInSheet=40|OwnerPartId=-1|Location.X=639|Location.Y=705|Color=8388608|FontID=1|IsHidden=T|Name=Voltage Rating - DC
|RECORD=41|OwnerIndex=898|IndexInSheet=41|OwnerPartId=-1|Location.X=639|Location.Y=705|Color=8388608|FontID=1|IsHidden=T|Name=Dielectric Material
|RECORD=34|OwnerIndex=898|IndexInSheet=-1|OwnerPartId=-1|Location.X=661|Location.Y=641|Color=8388608|FontID=1|Text=C2|Name=Designator|ReadOnlyState=1
|RECORD=41|OwnerIndex=898|IndexInSheet=-1|OwnerPartId=-1|Location.X=645|Location.Y=645|Color=8388608|FontID=1|IsHidden=T|Text=Murata_GRM155R61E105KA12D|Name=Comment
|RECORD=44|OwnerIndex=898
|RECORD=45|OwnerIndex=945|IndexInSheet=-1|Description=Chip Capacitor, Body 1.0x0.5mm, Hieght 0.55mm|UseComponentLibrary=T|ModelName=CAPC1005X055N|ModelType=PCBLIB|DatafileCount=1|ModelDatafileEntity0=CAPC1005X055N|ModelDatafileKind0=PCBLib|IsCurrent=T|DatalinksLocked=T|DatabaseDatalinksLocked=T
|RECORD=46|OwnerIndex=946
|RECORD=48|OwnerIndex=946
|RECORD=41|OwnerIndex=948|IndexInSheet=-1|OwnerPartId=-1|Color=8388608|FontID=1|IsHidden=T|Text=2D|Name=Available Preview Images
|RECORD=17|IndexInSheet=63|OwnerPartId=-1|Style=4|ShowNetName=F|Location.X=650|Location.Y=630|Orientation=3|Color=128|FontID=1|Text=GND
|RECORD=17|IndexInSheet=64|OwnerPartId=-1|Style=4|ShowNetName=F|Location.X=860|Location.Y=530|Orientation=3|Color=128|FontID=1|Text=GND
|RECORD=17|IndexInSheet=65|OwnerPartId=-1|Style=2|ShowNetName=T|Location.X=600|Location.Y=570|Orientation=1|Color=128|FontID=1|Text=VCC
|RECORD=1|LibReference=Capacitor_300mil|ComponentDescription=CAP, CER, X5R, 1UF, 10%, 25V, 0402, 0.55MM T|PartCount=2|DisplayModeCount=1|IndexInSheet=66|OwnerPartId=-1|Location.X=600|Location.Y=570|CurrentPartId=1|LibraryPath=*|SourceLibraryName=RL Research Altium Server|TargetFileName=*|AreaColor=11599871|Color=128|PartIDLocked=T|DesignItemId=CAP-CMP-00365-3|AllPinCount=2
|RECORD=13|OwnerIndex=953|IsNotAccesible=T|OwnerPartId=1|Location.X=590|Location.Y=558|Corner.X=610|Corner.Y=558|LineWidth=1|Color=16711680
|RECORD=6|OwnerIndex=953|IsNotAccesible=T|IndexInSheet=1|OwnerPartId=1|LineWidth=1|Color=16711680|LocationCount=2|X1=590|Y1=552|X2=610|Y2=552
|RECORD=6|OwnerIndex=953|IsNotAccesible=T|IndexInSheet=2|OwnerPartId=1|LineWidth=1|Color=16711680|LocationCount=2|X1=600|Y1=550|X2=600|Y2=552
|RECORD=6|OwnerIndex=953|IsNotAccesible=T|IndexInSheet=3|OwnerPartId=1|LineWidth=1|Color=16711680|LocationCount=2|X1=600|Y1=560|X2=600|Y2=558
|RECORD=2|OwnerIndex=953|OwnerPartId=1|FormalType=1|Electrical=4|PinConglomerate=33|PinLength=10|Location.X=600|Location.Y=560|Name=1|Designator=1|SwapIDPart=0|PinName_PositionConglomerate=16|Name_CustomFontID=16|PinDesignator_PositionConglomerate=16|Designator_CustomFontID=16|PinPropagationDelay=0.000000E+000
|RECORD=2|OwnerIndex=953|OwnerPartId=1|FormalType=1|Electrical=4|PinConglomerate=35|PinLength=10|Location.X=600|Location.Y=550|Name=2|Designator=2|SwapIDPart=0|PinName_PositionConglomerate=16|Name_CustomFontID=16|PinDesignator_PositionConglomerate=16|Designator_CustomFontID=16|PinPropagationDelay=0.000000E+000
|RECORD=41|OwnerIndex=953|IndexInSheet=6|OwnerPartId=-1|Location.X=589|Location.Y=585|Color=8388608|FontID=2|IsHidden=T|Text=https://www.digikey.com/en/products/detail/murata-electronics/GRM155R61E105KA12D/4905139?s=N4IgTCBcDaIOICUCyBGArGhA2FBRFADGgNICCKYAIiALoC%2BQA|Name=Datasheet URL
|RECORD=41|OwnerIndex=953|IndexInSheet=7|OwnerPartId=-1|Location.X=589|Location.Y=585|Color=8388608|FontID=1|IsHidden=T|Text=Yes|Name=RoHS
|RECORD=41|OwnerIndex=953|IndexInSheet=8|OwnerPartId=-1|Location.X=589|Location.Y=585|Color=8388608|FontID=1|IsHidden=T|Text=Surface Mount, MLCC|Name=Mounting Type
|RECORD=41|OwnerIndex=953|IndexInSheet=9|OwnerPartId=-1|Location.X=589|Location.Y=585|Color=8388608|FontID=1|IsHidden=T|Name=Voltage - Rated
|RECORD=41|OwnerIndex=953|IndexInSheet=10|OwnerPartId=-1|Location.X=589|Location.Y=585|Color=8388608|FontID=1|IsHidden=T|Text=85°C|Name=Max Operating Temperature
|RECORD=41|OwnerIndex=953|IndexInSheet=11|OwnerPartId=-1|Location.X=589|Location.Y=585|Color=8388608|FontID=1|IsHidden=T|Text=Ceramic Capacitors|Name=Category
|RECORD=41|OwnerIndex=953|IndexInSheet=12|OwnerPartId=-1|Location.X=589|Location.Y=585|Color=8388608|FontID=1|IsHidden=T|Text=0.022" (0.55mm)|Name=Height
|RECORD=41|OwnerIndex=953|IndexInSheet=13|OwnerPartId=-1|Location.X=589|Location.Y=585|Color=8388608|FontID=1|IsHidden=T|Name=Ratings
|RECORD=41|OwnerIndex=953|IndexInSheet=14|OwnerPartId=-1|Location.X=589|Location.Y=585|Color=8388608|FontID=1|IsHidden=T|Name=Lead Spacing
|RECORD=41|OwnerIndex=953|IndexInSheet=15|OwnerPartId=-1|Location.X=611|Location.Y=551|Color=8388608|FontID=1|Name=Part Status
|RECORD=41|OwnerIndex=953|IndexInSheet=16|OwnerPartId=-1|Location.X=589|Location.Y=585|Color=8388608|FontID=1|IsHidden=T|Text=Digikey|Name=Supplier 1
|RECORD=41|OwnerIndex=953|IndexInSheet=17|OwnerPartId=-1|Location.X=589|Location.Y=585|Color=8388608|FontID=1|IsHidden=T|Name=Lead Style
|RECORD=41|OwnerIndex=953|IndexInSheet=18|OwnerPartId=-1|Location.X=589|Location.Y=585|Color=8388608|FontID=1|IsHidden=T|Text=GRM155R61E105KA12D|Name=Manufacturer Part Number
|RECORD=41|OwnerIndex=953|IndexInSheet=19|OwnerPartId=-1|Location.X=589|Location.Y=585|Color=8388608|FontID=1|IsHidden=T|Name=Features
|RECORD=41|OwnerIndex=953|IndexInSheet=20|OwnerPartId=-1|Location.X=611|Location.Y=541|Color=8388608|FontID=1|Text=±10%|Name=Tolerance
|RECORD=41|OwnerIndex=953|IndexInSheet=21|OwnerPartId=-1|Location.X=611|Location.Y=531|Color=8388608|FontID=1|Text=25V|Name=Voltage Rating
|RECORD=41|OwnerIndex=953|IndexInSheet=22|OwnerPartId=-1|Location.X=589|Location.Y=605|Color=8388608|FontID=1|IsHidden=T|Text=X5R|Name=Temperature Coefficient
|RECORD=41|OwnerIndex=953|IndexInSheet=23|OwnerPartId=-1|Location.X=589|Location.Y=605|Color=8388608|FontID=1|IsHidden=T|Name=Voltage Rating - AC
|RECORD=41|OwnerIndex=953|IndexInSheet=24|OwnerPartId=-1|Location.X=589|Location.Y=605|Color=8388608|FontID=1|IsHidden=T|Text=-55°C|Name=Min Operating Temperature
|RECORD=41|OwnerIndex=953|IndexInSheet=25|OwnerPartId=-1|Location.X=589|Location.Y=605|Color=8388608|FontID=1|IsHidden=T|Name=Type
|RECORD=41|OwnerIndex=953|IndexInSheet=26|OwnerPartId=-1|Location.X=589|Location.Y=605|Color=8388608|FontID=1|IsHidden=T|Text=0402 (1005 Metric)|Name=Case/Package
|RECORD=41|OwnerIndex=953|IndexInSheet=27|OwnerPartId=-1|Location.X=589|Location.Y=605|Color=8388608|FontID=1|IsHidden=T|Text=Non-polar|Name=Polarization
|RECORD=41|OwnerIndex=953|IndexInSheet=28|OwnerPartId=-1|Location.X=589|Location.Y=605|Color=8388608|FontID=1|IsHidden=T|Text=Murata|Name=Manufacturer
|RECORD=41|OwnerIndex=953|IndexInSheet=29|OwnerPartId=-1|Location.X=589|Location.Y=605|Color=8388608|FontID=1|IsHidden=T|Text=0.039" L x 0.020" W (1.00mm x 0.50mm)|Name=Size / Dimension
|RECORD=41|OwnerIndex=953|IndexInSheet=30|OwnerPartId=-1|Location.X=589|Location.Y=605|Color=8388608|FontID=1|IsHidden=T|Name=Impedance
|RECORD=41|OwnerIndex=953|IndexInSheet=31|OwnerPartId=-1|Location.X=589|Location.Y=605|Color=8388608|FontID=1|IsHidden=T|Text=825-00099-00|Name=Internal Part Number
|RECORD=41|OwnerIndex=953|IndexInSheet=32|OwnerPartId=-1|Location.X=589|Location.Y=605|Color=8388608|FontID=1|IsHidden=T|Text=Ceramic|Name=Composition
|RECORD=41|OwnerIndex=953|IndexInSheet=33|OwnerPartId=-1|Location.X=589|Location.Y=605|Color=8388608|FontID=1|IsHidden=T|Name=Thickness (Max)
|RECORD=41|OwnerIndex=953|IndexInSheet=34|OwnerPartId=-1|Location.X=589|Location.Y=605|Color=8388608|FontID=1|IsHidden=T|Text=490-10017-1-ND|Name=Supplier Part Number 1
|RECORD=41|OwnerIndex=953|IndexInSheet=35|OwnerPartId=-1|Location.X=589|Location.Y=605|Color=8388608|FontID=1|IsHidden=T|Name=ESR (Equivalent Series Resistance)
|RECORD=41|OwnerIndex=953|IndexInSheet=36|OwnerPartId=-1|Location.X=589|Location.Y=605|Color=8388608|FontID=1|IsHidden=T|Text=GRM155R61E|Name=Series
|RECORD=41|OwnerIndex=953|IndexInSheet=37|OwnerPartId=-1|Location.X=589|Location.Y=605|Color=8388608|FontID=1|IsHidden=T|Name=Failure Rate
|RECORD=41|OwnerIndex=953|IndexInSheet=38|OwnerPartId=-1|Location.X=589|Location.Y=605|Color=8388608|FontID=1|IsHidden=T|Text=General Purpose|Name=Applications
|RECORD=41|OwnerIndex=953|IndexInSheet=39|OwnerPartId=-1|Location.X=611|Location.Y=521|Color=8388608|FontID=1|Text=1µF|Name=Capacitance
|RECORD=41|OwnerIndex=953|IndexInSheet=40|OwnerPartId=-1|Location.X=589|Location.Y=615|Color=8388608|FontID=1|IsHidden=T|Name=Voltage Rating - DC
|RECORD=41|OwnerIndex=953|IndexInSheet=41|OwnerPartId=-1|Location.X=589|Location.Y=615|Color=8388608|FontID=1|IsHidden=T|Name=Dielectric Material
|RECORD=34|OwnerIndex=953|IndexInSheet=-1|OwnerPartId=-1|Location.X=611|Location.Y=551|Color=8388608|FontID=1|Text=C3|Name=Designator|ReadOnlyState=1
|RECORD=41|OwnerIndex=953|IndexInSheet=-1|OwnerPartId=-1|Location.X=595|Location.Y=555|Color=8388608|FontID=1|IsHidden=T|Text=Murata_GRM155R61E105KA12D|Name=Comment
|RECORD=44|OwnerIndex=953
|RECORD=45|OwnerIndex=1000|IndexInSheet=-1|Description=Chip Capacitor, Body 1.0x0.5mm, Hieght 0.55mm|UseComponentLibrary=T|ModelName=CAPC1005X055N|ModelType=PCBLIB|DatafileCount=1|ModelDatafileEntity0=CAPC1005X055N|ModelDatafileKind0=PCBLib|IsCurrent=T|DatalinksLocked=T|DatabaseDatalinksLocked=T
|RECORD=46|OwnerIndex=1001
|RECORD=48|OwnerIndex=1001
|RECORD=41|OwnerIndex=1003|IndexInSheet=-1|OwnerPartId=-1|Color=8388608|FontID=1|IsHidden=T|Text=2D|Name=Available Preview Images
|RECORD=17|IndexInSheet=67|OwnerPartId=-1|Style=4|ShowNetName=F|Location.X=600|Location.Y=540|Orientation=3|Color=128|FontID=1|Text=GND
|RECORD=17|IndexInSheet=68|OwnerPartId=-1|Style=4|ShowNetName=F|Location.X=680|Location.Y=520|Orientation=3|Color=128|FontID=1|Text=GND
|RECORD=1|LibReference=TP_NoColor_001pin_No_BOM|ComponentDescription=TEST POINT, PC, SMT, 1.00MM DIA|PartCount=2|DisplayModeCount=1|IndexInSheet=69|OwnerPartId=-1|Location.X=690|Location.Y=490|Orientation=1|CurrentPartId=1|LibraryPath=*|SourceLibraryName=RL Research Altium Server|TargetFileName=*|AreaColor=11599871|Color=128|PartIDLocked=T|DesignItemId=TPS-CMP-00004-3|AllPinCount=1|ComponentKindVersion2=5
|RECORD=2|OwnerIndex=1007|OwnerPartId=1|FormalType=1|Electrical=4|PinConglomerate=33|PinLength=20|Location.X=700|Location.Y=510|Name=1|Designator=1|SwapIDPart=Ž&Ž||PinPropagationDelay=0.000000E+000
|RECORD=8|OwnerIndex=1007|IsNotAccesible=T|IndexInSheet=1|OwnerPartId=1|Location.X=700|Location.Y=500|Radius=5|SecondaryRadius=5|LineWidth=1|AreaColor=255
|RECORD=6|OwnerIndex=1007|IsNotAccesible=T|IndexInSheet=2|OwnerPartId=1|LineWidth=1|LocationCount=2|X1=700|Y1=510|X2=700|Y2=505
|RECORD=41|OwnerIndex=1007|IndexInSheet=3|OwnerPartId=-1|Location.X=695|Location.Y=532|Color=8388608|FontID=1|IsHidden=T|Name=Internal Part Number
|RECORD=41|OwnerIndex=1007|IndexInSheet=4|OwnerPartId=-1|Location.X=695|Location.Y=532|Color=8388608|FontID=1|IsHidden=T|Name=Pitch
|RECORD=41|OwnerIndex=1007|IndexInSheet=5|OwnerPartId=-1|Location.X=695|Location.Y=532|Color=8388608|FontID=1|IsHidden=T|Name=Color
|RECORD=41|OwnerIndex=1007|IndexInSheet=6|OwnerPartId=-1|Location.X=695|Location.Y=532|Color=8388608|FontID=1|IsHidden=T|Name=Min Operating Temperature
|RECORD=41|OwnerIndex=1007|IndexInSheet=7|OwnerPartId=-1|Location.X=695|Location.Y=532|Color=8388608|FontID=1|IsHidden=T|Name=Manufacturer Part Number
|RECORD=41|OwnerIndex=1007|IndexInSheet=8|OwnerPartId=-1|Location.X=695|Location.Y=532|Color=8388608|FontID=1|IsHidden=T|Name=Max Operating Temperature
|RECORD=41|OwnerIndex=1007|IndexInSheet=9|OwnerPartId=-1|Location.X=695|Location.Y=532|Color=8388608|FontID=1|IsHidden=T|Name=Supplier 1
|RECORD=41|OwnerIndex=1007|IndexInSheet=10|OwnerPartId=-1|Location.X=695|Location.Y=532|Color=8388608|FontID=1|IsHidden=T|Name=Material - Body
|RECORD=41|OwnerIndex=1007|IndexInSheet=11|OwnerPartId=-1|Location.X=695|Location.Y=532|Color=8388608|FontID=1|IsHidden=T|Name=Material - Insulation
|RECORD=41|OwnerIndex=1007|IndexInSheet=12|OwnerPartId=-1|Location.X=695|Location.Y=532|Color=8388608|FontID=1|IsHidden=T|Name=RoHS
|RECORD=41|OwnerIndex=1007|IndexInSheet=13|OwnerPartId=-1|Location.X=695|Location.Y=532|Color=8388608|FontID=1|IsHidden=T|Name=Plating
|RECORD=41|OwnerIndex=1007|IndexInSheet=14|OwnerPartId=-1|Location.X=695|Location.Y=532|Color=8388608|FontID=1|IsHidden=T|Text=PC Test Point, Surface Mount|Name=Type
|RECORD=41|OwnerIndex=1007|IndexInSheet=15|OwnerPartId=-1|Location.X=695|Location.Y=532|Color=8388608|FontID=1|IsHidden=T|Name=Manufacturer
|RECORD=41|OwnerIndex=1007|IndexInSheet=16|OwnerPartId=-1|Location.X=695|Location.Y=532|Color=8388608|FontID=1|IsHidden=T|Name=Datasheet URL
|RECORD=41|OwnerIndex=1007|IndexInSheet=17|OwnerPartId=-1|Location.X=695|Location.Y=532|Color=8388608|FontID=1|IsHidden=T|Name=Height
|RECORD=41|OwnerIndex=1007|IndexInSheet=18|OwnerPartId=-1|Location.X=695|Location.Y=532|Color=8388608|FontID=1|IsHidden=T|Text=1.00mm Dia Pad|Name=Size / Dimension
|RECORD=41|OwnerIndex=1007|IndexInSheet=19|OwnerPartId=-1|Location.X=695|Location.Y=532|Color=8388608|FontID=1|IsHidden=T|Name=Part Status
|RECORD=41|OwnerIndex=1007|IndexInSheet=20|OwnerPartId=-1|Location.X=695|Location.Y=532|Color=8388608|FontID=1|IsHidden=T|Name=Supplier Part Number 1
|RECORD=41|OwnerIndex=1007|IndexInSheet=21|OwnerPartId=-1|Location.X=695|Location.Y=532|Color=8388608|FontID=1|IsHidden=T|Text=Test Points|Name=Category
|RECORD=41|OwnerIndex=1007|IndexInSheet=22|OwnerPartId=-1|Location.X=695|Location.Y=532|Color=8388608|FontID=1|IsHidden=T|Text=1.00mm Dia Pad|Name=Mounting Type
|RECORD=41|OwnerIndex=1007|IndexInSheet=23|OwnerPartId=-1|Location.X=695|Location.Y=532|Color=8388608|FontID=1|IsHidden=T|Name=Series
|RECORD=34|OwnerIndex=1007|IndexInSheet=-1|OwnerPartId=-1|Location.X=695|Location.Y=475|Color=8388608|FontID=1|Text=TP1|Name=Designator|ReadOnlyState=1
|RECORD=41|OwnerIndex=1007|IndexInSheet=-1|OwnerPartId=-1|Location.X=695|Location.Y=532|Color=8388608|FontID=1|IsHidden=T|Text=SMT_100DIA|Name=Comment
|RECORD=44|OwnerIndex=1007
|RECORD=45|OwnerIndex=1035|IndexInSheet=-1|Description=Test Point, 1pin, Surface Mount 1.00mm Diameter|UseComponentLibrary=T|ModelName=TP001V_SMT_100DIA|ModelType=PCBLIB|DatafileCount=1|ModelDatafileEntity0=TP001V_SMT_100DIA|ModelDatafileKind0=PCBLib|IsCurrent=T|DatalinksLocked=T|DatabaseDatalinksLocked=T
|RECORD=46|OwnerIndex=1036
|RECORD=48|OwnerIndex=1036
|RECORD=41|OwnerIndex=1038|IndexInSheet=-1|OwnerPartId=-1|Color=8388608|FontID=1|IsHidden=T|Text=2D|Name=Available Preview Images
|RECORD=25|IndexInSheet=70|OwnerPartId=-1|Location.X=890|Location.Y=430|Justification=2|Color=128|FontID=1|Text=TP1
|RECORD=25|IndexInSheet=71|OwnerPartId=-1|Location.X=890|Location.Y=420|Justification=2|Color=128|FontID=1|Text=TP2
|RECORD=25|IndexInSheet=72|OwnerPartId=-1|Location.X=680|Location.Y=380|Color=128|FontID=1|Text=TXD
|RECORD=25|IndexInSheet=73|OwnerPartId=-1|Location.X=680|Location.Y=370|Color=128|FontID=1|Text=RXD
|RECORD=17|IndexInSheet=74|OwnerPartId=-1|Style=4|ShowNetName=F|Location.X=620|Location.Y=390|Orientation=3|Color=128|FontID=1|Text=GND
|RECORD=1|LibReference=Capacitor_300mil|ComponentDescription=CAP, CER, X5R, 1UF, 10%, 25V, 0402, 0.55MM T|PartCount=2|DisplayModeCount=1|IndexInSheet=75|OwnerPartId=-1|Location.X=620|Location.Y=420|IsMirrored=T|CurrentPartId=1|LibraryPath=*|SourceLibraryName=RL Research Altium Server|TargetFileName=*|AreaColor=11599871|Color=128|PartIDLocked=T|DesignItemId=CAP-CMP-00365-3|AllPinCount=2
|RECORD=13|OwnerIndex=1045|IsNotAccesible=T|OwnerPartId=1|Location.X=630|Location.Y=408|Corner.X=610|Corner.Y=408|LineWidth=1|Color=16711680
|RECORD=6|OwnerIndex=1045|IsNotAccesible=T|IndexInSheet=1|OwnerPartId=1|LineWidth=1|Color=16711680|LocationCount=2|X1=630|Y1=402|X2=610|Y2=402
|RECORD=6|OwnerIndex=1045|IsNotAccesible=T|IndexInSheet=2|OwnerPartId=1|LineWidth=1|Color=16711680|LocationCount=2|X1=620|Y1=400|X2=620|Y2=402
|RECORD=6|OwnerIndex=1045|IsNotAccesible=T|IndexInSheet=3|OwnerPartId=1|LineWidth=1|Color=16711680|LocationCount=2|X1=620|Y1=410|X2=620|Y2=408
|RECORD=2|OwnerIndex=1045|OwnerPartId=1|FormalType=1|Electrical=4|PinConglomerate=33|PinLength=10|Location.X=620|Location.Y=410|Name=1|Designator=1|SwapIDPart=0|PinName_PositionConglomerate=16|Name_CustomFontID=16|PinDesignator_PositionConglomerate=16|Designator_CustomFontID=16|PinPropagationDelay=0.000000E+000
|RECORD=2|OwnerIndex=1045|OwnerPartId=1|FormalType=1|Electrical=4|PinConglomerate=35|PinLength=10|Location.X=620|Location.Y=400|Name=2|Designator=2|SwapIDPart=0|PinName_PositionConglomerate=16|Name_CustomFontID=16|PinDesignator_PositionConglomerate=16|Designator_CustomFontID=16|PinPropagationDelay=0.000000E+000
|RECORD=41|OwnerIndex=1045|IndexInSheet=6|OwnerPartId=-1|Location.X=609|Location.Y=422|Color=8388608|FontID=2|IsHidden=T|Text=https://www.digikey.com/en/products/detail/murata-electronics/GRM155R61E105KA12D/4905139?s=N4IgTCBcDaIOICUCyBGArGhA2FBRFADGgNICCKYAIiALoC%2BQA|Name=Datasheet URL|IsMirrored=T
|RECORD=41|OwnerIndex=1045|IndexInSheet=7|OwnerPartId=-1|Location.X=609|Location.Y=422|Color=8388608|FontID=1|IsHidden=T|Text=Yes|Name=RoHS|IsMirrored=T
|RECORD=41|OwnerIndex=1045|IndexInSheet=8|OwnerPartId=-1|Location.X=609|Location.Y=422|Color=8388608|FontID=1|IsHidden=T|Text=Surface Mount, MLCC|Name=Mounting Type|IsMirrored=T
|RECORD=41|OwnerIndex=1045|IndexInSheet=9|OwnerPartId=-1|Location.X=609|Location.Y=422|Color=8388608|FontID=1|IsHidden=T|Name=Voltage - Rated|IsMirrored=T
|RECORD=41|OwnerIndex=1045|IndexInSheet=10|OwnerPartId=-1|Location.X=609|Location.Y=422|Color=8388608|FontID=1|IsHidden=T|Text=85°C|Name=Max Operating Temperature|IsMirrored=T
|RECORD=41|OwnerIndex=1045|IndexInSheet=11|OwnerPartId=-1|Location.X=609|Location.Y=422|Color=8388608|FontID=1|IsHidden=T|Text=Ceramic Capacitors|Name=Category|IsMirrored=T
|RECORD=41|OwnerIndex=1045|IndexInSheet=12|OwnerPartId=-1|Location.X=609|Location.Y=422|Color=8388608|FontID=1|IsHidden=T|Text=0.022" (0.55mm)|Name=Height|IsMirrored=T
|RECORD=41|OwnerIndex=1045|IndexInSheet=13|OwnerPartId=-1|Location.X=609|Location.Y=422|Color=8388608|FontID=1|IsHidden=T|Name=Ratings|IsMirrored=T
|RECORD=41|OwnerIndex=1045|IndexInSheet=14|OwnerPartId=-1|Location.X=609|Location.Y=422|Color=8388608|FontID=1|IsHidden=T|Name=Lead Spacing|IsMirrored=T
|RECORD=41|OwnerIndex=1045|IndexInSheet=15|OwnerPartId=-1|Location.X=631|Location.Y=401|Color=8388608|FontID=1|Name=Part Status|IsMirrored=T
|RECORD=41|OwnerIndex=1045|IndexInSheet=16|OwnerPartId=-1|Location.X=609|Location.Y=422|Color=8388608|FontID=1|IsHidden=T|Text=Digikey|Name=Supplier 1|IsMirrored=T
|RECORD=41|OwnerIndex=1045|IndexInSheet=17|OwnerPartId=-1|Location.X=609|Location.Y=422|Color=8388608|FontID=1|IsHidden=T|Name=Lead Style|IsMirrored=T
|RECORD=41|OwnerIndex=1045|IndexInSheet=18|OwnerPartId=-1|Location.X=609|Location.Y=422|Color=8388608|FontID=1|IsHidden=T|Text=GRM155R61E105KA12D|Name=Manufacturer Part Number|IsMirrored=T
|RECORD=41|OwnerIndex=1045|IndexInSheet=19|OwnerPartId=-1|Location.X=609|Location.Y=422|Color=8388608|FontID=1|IsHidden=T|Name=Features|IsMirrored=T
|RECORD=41|OwnerIndex=1045|IndexInSheet=20|OwnerPartId=-1|Location.X=631|Location.Y=391|Color=8388608|FontID=1|Text=±10%|Name=Tolerance|IsMirrored=T
|RECORD=41|OwnerIndex=1045|IndexInSheet=21|OwnerPartId=-1|Location.X=631|Location.Y=381|Color=8388608|FontID=1|Text=25V|Name=Voltage Rating|IsMirrored=T
|RECORD=41|OwnerIndex=1045|IndexInSheet=22|OwnerPartId=-1|Location.X=609|Location.Y=422|Color=8388608|FontID=1|IsHidden=T|Text=X5R|Name=Temperature Coefficient|IsMirrored=T
|RECORD=41|OwnerIndex=1045|IndexInSheet=23|OwnerPartId=-1|Location.X=609|Location.Y=422|Color=8388608|FontID=1|IsHidden=T|Name=Voltage Rating - AC|IsMirrored=T
|RECORD=41|OwnerIndex=1045|IndexInSheet=24|OwnerPartId=-1|Location.X=609|Location.Y=422|Color=8388608|FontID=1|IsHidden=T|Text=-55°C|Name=Min Operating Temperature|IsMirrored=T
|RECORD=41|OwnerIndex=1045|IndexInSheet=25|OwnerPartId=-1|Location.X=609|Location.Y=422|Color=8388608|FontID=1|IsHidden=T|Name=Type|IsMirrored=T
|RECORD=41|OwnerIndex=1045|IndexInSheet=26|OwnerPartId=-1|Location.X=609|Location.Y=422|Color=8388608|FontID=1|IsHidden=T|Text=0402 (1005 Metric)|Name=Case/Package|IsMirrored=T
|RECORD=41|OwnerIndex=1045|IndexInSheet=27|OwnerPartId=-1|Location.X=609|Location.Y=422|Color=8388608|FontID=1|IsHidden=T|Text=Non-polar|Name=Polarization|IsMirrored=T
|RECORD=41|OwnerIndex=1045|IndexInSheet=28|OwnerPartId=-1|Location.X=609|Location.Y=422|Color=8388608|FontID=1|IsHidden=T|Text=Murata|Name=Manufacturer|IsMirrored=T
|RECORD=41|OwnerIndex=1045|IndexInSheet=29|OwnerPartId=-1|Location.X=609|Location.Y=422|Color=8388608|FontID=1|IsHidden=T|Text=0.039" L x 0.020" W (1.00mm x 0.50mm)|Name=Size / Dimension|IsMirrored=T
|RECORD=41|OwnerIndex=1045|IndexInSheet=30|OwnerPartId=-1|Location.X=609|Location.Y=422|Color=8388608|FontID=1|IsHidden=T|Name=Impedance|IsMirrored=T
|RECORD=41|OwnerIndex=1045|IndexInSheet=31|OwnerPartId=-1|Location.X=609|Location.Y=422|Color=8388608|FontID=1|IsHidden=T|Text=825-00099-00|Name=Internal Part Number|IsMirrored=T
|RECORD=41|OwnerIndex=1045|IndexInSheet=32|OwnerPartId=-1|Location.X=609|Location.Y=422|Color=8388608|FontID=1|IsHidden=T|Text=Ceramic|Name=Composition|IsMirrored=T
|RECORD=41|OwnerIndex=1045|IndexInSheet=33|OwnerPartId=-1|Location.X=609|Location.Y=422|Color=8388608|FontID=1|IsHidden=T|Name=Thickness (Max)|IsMirrored=T
|RECORD=41|OwnerIndex=1045|IndexInSheet=34|OwnerPartId=-1|Location.X=609|Location.Y=422|Color=8388608|FontID=1|IsHidden=T|Text=490-10017-1-ND|Name=Supplier Part Number 1|IsMirrored=T
|RECORD=41|OwnerIndex=1045|IndexInSheet=35|OwnerPartId=-1|Location.X=609|Location.Y=422|Color=8388608|FontID=1|IsHidden=T|Name=ESR (Equivalent Series Resistance)|IsMirrored=T
|RECORD=41|OwnerIndex=1045|IndexInSheet=36|OwnerPartId=-1|Location.X=609|Location.Y=422|Color=8388608|FontID=1|IsHidden=T|Text=GRM155R61E|Name=Series|IsMirrored=T
|RECORD=41|OwnerIndex=1045|IndexInSheet=37|OwnerPartId=-1|Location.X=609|Location.Y=422|Color=8388608|FontID=1|IsHidden=T|Name=Failure Rate|IsMirrored=T
|RECORD=41|OwnerIndex=1045|IndexInSheet=38|OwnerPartId=-1|Location.X=609|Location.Y=422|Color=8388608|FontID=1|IsHidden=T|Text=General Purpose|Name=Applications|IsMirrored=T
|RECORD=41|OwnerIndex=1045|IndexInSheet=39|OwnerPartId=-1|Location.X=631|Location.Y=371|Color=8388608|FontID=1|Text=1µF|Name=Capacitance|IsMirrored=T
|RECORD=41|OwnerIndex=1045|IndexInSheet=40|OwnerPartId=-1|Location.X=609|Location.Y=422|Color=8388608|FontID=1|IsHidden=T|Name=Voltage Rating - DC|IsMirrored=T
|RECORD=41|OwnerIndex=1045|IndexInSheet=41|OwnerPartId=-1|Location.X=609|Location.Y=422|Color=8388608|FontID=1|IsHidden=T|Name=Dielectric Material|IsMirrored=T
|RECORD=34|OwnerIndex=1045|IndexInSheet=-1|OwnerPartId=-1|Location.X=631|Location.Y=401|Color=8388608|FontID=1|Text=C5|Name=Designator|ReadOnlyState=1|IsMirrored=T
|RECORD=41|OwnerIndex=1045|IndexInSheet=-1|OwnerPartId=-1|Location.X=609|Location.Y=422|Color=8388608|FontID=1|IsHidden=T|Text=Murata_GRM155R61E105KA12D|Name=Comment|IsMirrored=T
|RECORD=44|OwnerIndex=1045
|RECORD=45|OwnerIndex=1092|IndexInSheet=-1|Description=Chip Capacitor, Body 1.0x0.5mm, Hieght 0.55mm|UseComponentLibrary=T|ModelName=CAPC1005X055N|ModelType=PCBLIB|DatafileCount=1|ModelDatafileEntity0=CAPC1005X055N|ModelDatafileKind0=PCBLib|IsCurrent=T|DatalinksLocked=T|DatabaseDatalinksLocked=T
|RECORD=46|OwnerIndex=1093
|RECORD=48|OwnerIndex=1093
|RECORD=41|OwnerIndex=1095|IndexInSheet=-1|OwnerPartId=-1|Color=8388608|FontID=1|IsHidden=T|Text=2D|Name=Available Preview Images
|RECORD=1|LibReference=1029c3af85768c4190bb7ad29bc67b5|ComponentDescription=1kO ±1% 0.063W 0402 Thick Film Chip Resistor AEC-Q200 compliant|PartCount=2|DisplayModeCount=1|IndexInSheet=76|OwnerPartId=-1|Location.X=620|Location.Y=430|Orientation=1|CurrentPartId=1|LibraryPath=*|SourceLibraryName=Altium Content Vault|TargetFileName=*|AreaColor=11599871|Color=128|PartIDLocked=T|DesignItemId=CMP-26527-000026-1|AllPinCount=2
|RECORD=2|OwnerIndex=1097|OwnerPartId=1|Electrical=4|PinConglomerate=35|PinLength=20|Location.X=620|Location.Y=450|Name=1|Designator=1|PinPropagationDelay=0.000000E+000
|RECORD=2|OwnerIndex=1097|OwnerPartId=1|Electrical=4|PinConglomerate=33|PinLength=20|Location.X=620|Location.Y=480|Name=2|Designator=2|PinPropagationDelay=0.000000E+000
|RECORD=13|OwnerIndex=1097|IsNotAccesible=T|IndexInSheet=2|OwnerPartId=1|Location.X=620|Location.Y=450|Corner.X=615|Corner.Y=453|LineWidth=1|Color=16711680
|RECORD=13|OwnerIndex=1097|IsNotAccesible=T|IndexInSheet=3|OwnerPartId=1|Location.X=615|Location.Y=453|Corner.X=625|Corner.Y=458|LineWidth=1|Color=16711680
|RECORD=13|OwnerIndex=1097|IsNotAccesible=T|IndexInSheet=4|OwnerPartId=1|Location.X=625|Location.Y=458|Corner.X=615|Corner.Y=463|LineWidth=1|Color=16711680
|RECORD=13|OwnerIndex=1097|IsNotAccesible=T|IndexInSheet=5|OwnerPartId=1|Location.X=615|Location.Y=463|Corner.X=625|Corner.Y=468|LineWidth=1|Color=16711680
|RECORD=13|OwnerIndex=1097|IsNotAccesible=T|IndexInSheet=6|OwnerPartId=1|Location.X=625|Location.Y=468|Corner.X=615|Corner.Y=473|LineWidth=1|Color=16711680
|RECORD=13|OwnerIndex=1097|IsNotAccesible=T|IndexInSheet=7|OwnerPartId=1|Location.X=615|Location.Y=473|Corner.X=625|Corner.Y=478|LineWidth=1|Color=16711680
|RECORD=13|OwnerIndex=1097|IsNotAccesible=T|IndexInSheet=8|OwnerPartId=1|Location.X=625|Location.Y=478|Corner.X=620|Corner.Y=480|LineWidth=1|Color=16711680
|RECORD=13|OwnerIndex=1097|IsNotAccesible=T|IndexInSheet=9|OwnerPartId=1|Location.X=620|Location.Y=450|Corner.X=620|Corner.Y=447|LineWidth=1|Color=16711680
|RECORD=13|OwnerIndex=1097|IsNotAccesible=T|IndexInSheet=10|OwnerPartId=1|Location.X=620|Location.Y=480|Corner.X=620|Corner.Y=483|LineWidth=1|Color=16711680
|RECORD=41|OwnerIndex=1097|IndexInSheet=11|OwnerPartId=-1|Location.X=614|Location.Y=502|Color=8388608|FontID=1|IsHidden=T|Text=1mm|Name=Length
|RECORD=41|OwnerIndex=1097|IndexInSheet=12|OwnerPartId=-1|Location.X=614|Location.Y=502|Color=8388608|FontID=1|IsHidden=T|Text=Yes|Name=RoHS Compliant
|RECORD=41|OwnerIndex=1097|IndexInSheet=13|OwnerPartId=-1|Location.X=614|Location.Y=502|Color=8388608|FontID=1|IsHidden=T|Text=Rectangular|Name=Construction
|RECORD=41|OwnerIndex=1097|IndexInSheet=14|OwnerPartId=-1|Location.X=614|Location.Y=502|Color=8388608|FontID=1|IsHidden=T|Text=0.016inch|Name=Height
|RECORD=41|OwnerIndex=1097|IndexInSheet=15|OwnerPartId=-1|Location.X=614|Location.Y=502|Color=8388608|FontID=1|IsHidden=T|Text=0402|Name=Size Code
|RECORD=41|OwnerIndex=1097|IndexInSheet=16|OwnerPartId=-1|Location.X=614|Location.Y=502|Color=8388608|FontID=1|IsHidden=T|Text=Lead Free|Name=Lead Free
|RECORD=41|OwnerIndex=1097|IndexInSheet=17|OwnerPartId=-1|Location.X=614|Location.Y=502|Color=8388608|FontID=1|IsHidden=T|Text=No|Name=Radiation Hardening
|RECORD=41|OwnerIndex=1097|IndexInSheet=18|OwnerPartId=-1|Location.X=614|Location.Y=502|Color=8388608|FontID=1|IsHidden=T|Text=1%|Name=Tolerance
|RECORD=41|OwnerIndex=1097|IndexInSheet=19|OwnerPartId=-1|Location.X=614|Location.Y=502|Color=8388608|FontID=1|IsHidden=T|Text=0.02inch|Name=Width
|RECORD=41|OwnerIndex=1097|IndexInSheet=20|OwnerPartId=-1|Location.X=614|Location.Y=502|Color=8388608|FontID=1|IsHidden=T|Text=1kR|Name=Resistance
|RECORD=41|OwnerIndex=1097|IndexInSheet=21|OwnerPartId=-1|Location.X=614|Location.Y=502|Color=8388608|FontID=1|IsHidden=T|Text=Not|Name=Military Standard
|RECORD=41|OwnerIndex=1097|IndexInSheet=22|OwnerPartId=-1|Location.X=614|Location.Y=502|Color=8388608|FontID=1|IsHidden=T|Text=Thick Film|Name=Resistor Type
|RECORD=41|OwnerIndex=1097|IndexInSheet=23|OwnerPartId=-1|Location.X=614|Location.Y=502|Color=8388608|FontID=1|IsHidden=T|Text=100ppm/°C|Name=Temperature Coefficient
|RECORD=41|OwnerIndex=1097|IndexInSheet=24|OwnerPartId=-1|Location.X=614|Location.Y=502|Color=8388608|FontID=1|IsHidden=T|Text=2|Name=Number of Terminations
|RECORD=41|OwnerIndex=1097|IndexInSheet=25|OwnerPartId=-1|Location.X=614|Location.Y=502|Color=8388608|FontID=1|IsHidden=T|Text=-55°C|Name=Min Operating Temperature
|RECORD=41|OwnerIndex=1097|IndexInSheet=26|OwnerPartId=-1|Location.X=614|Location.Y=502|Color=8388608|FontID=1|IsHidden=T|Text=155°C|Name=Max Operating Temperature
|RECORD=41|OwnerIndex=1097|IndexInSheet=27|OwnerPartId=-1|Location.X=614|Location.Y=502|Color=8388608|FontID=1|IsHidden=T|Text=63mW|Name=Power Rating
|RECORD=41|OwnerIndex=1097|IndexInSheet=28|OwnerPartId=-1|Location.X=614|Location.Y=502|Color=8388608|FontID=1|IsHidden=T|Text=0.5mm|Name=Depth
|RECORD=41|OwnerIndex=1097|IndexInSheet=29|OwnerPartId=-1|Location.X=614|Location.Y=502|Color=8388608|FontID=1|IsHidden=T|Text=Automotive AEC-Q200|Name=Features
|RECORD=41|OwnerIndex=1097|IndexInSheet=30|OwnerPartId=-1|Location.X=614|Location.Y=502|Color=8388608|FontID=1|IsHidden=T|Text=Tape and Reel|Name=Packaging
|RECORD=41|OwnerIndex=1097|IndexInSheet=31|OwnerPartId=-1|Location.X=614|Location.Y=502|Color=8388608|FontID=1|IsHidden=T|Text=1005|Name=Case Code (Metric)
|RECORD=41|OwnerIndex=1097|IndexInSheet=32|OwnerPartId=-1|Location.X=614|Location.Y=502|Color=8388608|FontID=1|IsHidden=T|Text=Surface Mount|Name=Mount
|RECORD=41|OwnerIndex=1097|IndexInSheet=33|OwnerPartId=-1|Location.X=614|Location.Y=502|Color=8388608|FontID=1|IsHidden=T|Text=Tin|Name=Contact Plating
|RECORD=41|OwnerIndex=1097|IndexInSheet=34|OwnerPartId=-1|Location.X=614|Location.Y=502|Color=8388608|FontID=1|IsHidden=T|Text=63mW|Name=Max Power Dissipation
|RECORD=41|OwnerIndex=1097|IndexInSheet=35|OwnerPartId=-1|Location.X=614|Location.Y=502|Color=8388608|FontID=1|IsHidden=T|Text=0402|Name=Case/Package
|RECORD=41|OwnerIndex=1097|IndexInSheet=36|OwnerPartId=-1|Location.X=614|Location.Y=502|Color=8388608|FontID=1|IsHidden=T|Text=0402|Name=Case Code (Imperial)
|RECORD=41|OwnerIndex=1097|IndexInSheet=37|OwnerPartId=-1|Location.X=614|Location.Y=502|Color=8388608|FontID=1|IsHidden=T|Text=RMCF|Name=Series
|RECORD=34|OwnerIndex=1097|IndexInSheet=-1|OwnerPartId=-1|Location.X=626|Location.Y=474|Color=8388608|FontID=1|Text=R1|Name=Designator|ReadOnlyState=1
|RECORD=41|OwnerIndex=1097|IndexInSheet=-1|OwnerPartId=1|Location.X=626|Location.Y=464|Color=8388608|FontID=1|Text=1k|Name=Comment
|RECORD=44|OwnerIndex=1097
|RECORD=45|OwnerIndex=1140|IndexInSheet=-1|UseComponentLibrary=T|ModelName=FP-RMCF0402-MFG|ModelType=PCBLIB|DatafileCount=1|ModelDatafileEntity0=FP-RMCF0402-MFG|ModelDatafileKind0=PCBLib|IsCurrent=T|DatalinksLocked=T|DatabaseDatalinksLocked=T
|RECORD=46|OwnerIndex=1141
|RECORD=48|OwnerIndex=1141
|RECORD=45|OwnerIndex=1140|IndexInSheet=-1|UseComponentLibrary=T|ModelName=FP-RMCF0402-IPC_C|ModelType=PCBLIB|DatafileCount=1|ModelDatafileEntity0=FP-RMCF0402-IPC_C|ModelDatafileKind0=PCBLib|DatalinksLocked=T|DatabaseDatalinksLocked=T
|RECORD=46|OwnerIndex=1144
|RECORD=48|OwnerIndex=1144
|RECORD=45|OwnerIndex=1140|IndexInSheet=-1|UseComponentLibrary=T|ModelName=FP-RMCF0402-IPC_B|ModelType=PCBLIB|DatafileCount=1|ModelDatafileEntity0=FP-RMCF0402-IPC_B|ModelDatafileKind0=PCBLib|DatalinksLocked=T|DatabaseDatalinksLocked=T
|RECORD=46|OwnerIndex=1147
|RECORD=48|OwnerIndex=1147
|RECORD=45|OwnerIndex=1140|IndexInSheet=-1|UseComponentLibrary=T|ModelName=FP-RMCF0402-IPC_A|ModelType=PCBLIB|DatafileCount=1|ModelDatafileEntity0=FP-RMCF0402-IPC_A|ModelDatafileKind0=PCBLib|DatalinksLocked=T|DatabaseDatalinksLocked=T
|RECORD=46|OwnerIndex=1150
|RECORD=48|OwnerIndex=1150
|RECORD=17|IndexInSheet=77|OwnerPartId=-1|Style=2|ShowNetName=T|Location.X=620|Location.Y=500|Orientation=1|Color=128|FontID=1|Text=VCC
|RECORD=1|LibReference=TP_NoColor_001pin_No_BOM|ComponentDescription=TEST POINT, PC, SMT, 1.00MM DIA|PartCount=2|DisplayModeCount=1|IndexInSheet=78|OwnerPartId=-1|Location.X=660|Location.Y=420|CurrentPartId=1|LibraryPath=*|SourceLibraryName=RL Research Altium Server|TargetFileName=*|AreaColor=11599871|Color=128|PartIDLocked=T|DesignItemId=TPS-CMP-00004-3|AllPinCount=1|ComponentKindVersion2=5
|RECORD=2|OwnerIndex=1154|OwnerPartId=1|FormalType=1|Electrical=4|PinConglomerate=32|PinLength=20|Location.X=680|Location.Y=410|Name=1|Designator=1|SwapIDPart=Ž&Ž||PinPropagationDelay=0.000000E+000
|RECORD=8|OwnerIndex=1154|IsNotAccesible=T|IndexInSheet=1|OwnerPartId=1|Location.X=670|Location.Y=410|Radius=5|SecondaryRadius=5|LineWidth=1|AreaColor=255
|RECORD=6|OwnerIndex=1154|IsNotAccesible=T|IndexInSheet=2|OwnerPartId=1|LineWidth=1|LocationCount=2|X1=680|Y1=410|X2=675|Y2=410
|RECORD=41|OwnerIndex=1154|IndexInSheet=3|OwnerPartId=-1|Location.X=665|Location.Y=415|Color=8388608|FontID=1|IsHidden=T|Name=Internal Part Number
|RECORD=41|OwnerIndex=1154|IndexInSheet=4|OwnerPartId=-1|Location.X=665|Location.Y=415|Color=8388608|FontID=1|IsHidden=T|Name=Pitch
|RECORD=41|OwnerIndex=1154|IndexInSheet=5|OwnerPartId=-1|Location.X=665|Location.Y=415|Color=8388608|FontID=1|IsHidden=T|Name=Color
|RECORD=41|OwnerIndex=1154|IndexInSheet=6|OwnerPartId=-1|Location.X=665|Location.Y=415|Color=8388608|FontID=1|IsHidden=T|Name=Min Operating Temperature
|RECORD=41|OwnerIndex=1154|IndexInSheet=7|OwnerPartId=-1|Location.X=665|Location.Y=415|Color=8388608|FontID=1|IsHidden=T|Name=Manufacturer Part Number
|RECORD=41|OwnerIndex=1154|IndexInSheet=8|OwnerPartId=-1|Location.X=665|Location.Y=415|Color=8388608|FontID=1|IsHidden=T|Name=Max Operating Temperature
|RECORD=41|OwnerIndex=1154|IndexInSheet=9|OwnerPartId=-1|Location.X=665|Location.Y=415|Color=8388608|FontID=1|IsHidden=T|Name=Supplier 1
|RECORD=41|OwnerIndex=1154|IndexInSheet=10|OwnerPartId=-1|Location.X=665|Location.Y=415|Color=8388608|FontID=1|IsHidden=T|Name=Material - Body
|RECORD=41|OwnerIndex=1154|IndexInSheet=11|OwnerPartId=-1|Location.X=665|Location.Y=415|Color=8388608|FontID=1|IsHidden=T|Name=Material - Insulation
|RECORD=41|OwnerIndex=1154|IndexInSheet=12|OwnerPartId=-1|Location.X=665|Location.Y=415|Color=8388608|FontID=1|IsHidden=T|Name=RoHS
|RECORD=41|OwnerIndex=1154|IndexInSheet=13|OwnerPartId=-1|Location.X=665|Location.Y=415|Color=8388608|FontID=1|IsHidden=T|Name=Plating
|RECORD=41|OwnerIndex=1154|IndexInSheet=14|OwnerPartId=-1|Location.X=665|Location.Y=415|Color=8388608|FontID=1|IsHidden=T|Text=PC Test Point, Surface Mount|Name=Type
|RECORD=41|OwnerIndex=1154|IndexInSheet=15|OwnerPartId=-1|Location.X=665|Location.Y=415|Color=8388608|FontID=1|IsHidden=T|Name=Manufacturer
|RECORD=41|OwnerIndex=1154|IndexInSheet=16|OwnerPartId=-1|Location.X=665|Location.Y=415|Color=8388608|FontID=1|IsHidden=T|Name=Datasheet URL
|RECORD=41|OwnerIndex=1154|IndexInSheet=17|OwnerPartId=-1|Location.X=665|Location.Y=415|Color=8388608|FontID=1|IsHidden=T|Name=Height
|RECORD=41|OwnerIndex=1154|IndexInSheet=18|OwnerPartId=-1|Location.X=665|Location.Y=415|Color=8388608|FontID=1|IsHidden=T|Text=1.00mm Dia Pad|Name=Size / Dimension
|RECORD=41|OwnerIndex=1154|IndexInSheet=19|OwnerPartId=-1|Location.X=665|Location.Y=415|Color=8388608|FontID=1|IsHidden=T|Name=Part Status
|RECORD=41|OwnerIndex=1154|IndexInSheet=20|OwnerPartId=-1|Location.X=665|Location.Y=415|Color=8388608|FontID=1|IsHidden=T|Name=Supplier Part Number 1
|RECORD=41|OwnerIndex=1154|IndexInSheet=21|OwnerPartId=-1|Location.X=665|Location.Y=415|Color=8388608|FontID=1|IsHidden=T|Text=Test Points|Name=Category
|RECORD=41|OwnerIndex=1154|IndexInSheet=22|OwnerPartId=-1|Location.X=665|Location.Y=415|Color=8388608|FontID=1|IsHidden=T|Text=1.00mm Dia Pad|Name=Mounting Type
|RECORD=41|OwnerIndex=1154|IndexInSheet=23|OwnerPartId=-1|Location.X=665|Location.Y=415|Color=8388608|FontID=1|IsHidden=T|Name=Series
|RECORD=34|OwnerIndex=1154|IndexInSheet=-1|OwnerPartId=-1|Location.X=650|Location.Y=410|Color=8388608|FontID=1|Text=TP2|Name=Designator|ReadOnlyState=1
|RECORD=41|OwnerIndex=1154|IndexInSheet=-1|OwnerPartId=-1|Location.X=665|Location.Y=415|Color=8388608|FontID=1|IsHidden=T|Text=SMT_100DIA|Name=Comment
|RECORD=44|OwnerIndex=1154
|RECORD=45|OwnerIndex=1182|IndexInSheet=-1|Description=Test Point, 1pin, Surface Mount 1.00mm Diameter|UseComponentLibrary=T|ModelName=TP001V_SMT_100DIA|ModelType=PCBLIB|DatafileCount=1|ModelDatafileEntity0=TP001V_SMT_100DIA|ModelDatafileKind0=PCBLib|IsCurrent=T|DatalinksLocked=T|DatabaseDatalinksLocked=T
|RECORD=46|OwnerIndex=1183
|RECORD=48|OwnerIndex=1183
|RECORD=41|OwnerIndex=1185|IndexInSheet=-1|OwnerPartId=-1|Color=8388608|FontID=1|IsHidden=T|Text=2D|Name=Available Preview Images
|RECORD=1|LibReference=TP_NoColor_001pin_No_BOM|ComponentDescription=TEST POINT, PC, SMT, 1.00MM DIA|PartCount=2|DisplayModeCount=1|IndexInSheet=79|OwnerPartId=-1|Location.X=660|Location.Y=410|CurrentPartId=1|LibraryPath=*|SourceLibraryName=RL Research Altium Server|TargetFileName=*|AreaColor=11599871|Color=128|PartIDLocked=T|DesignItemId=TPS-CMP-00004-3|AllPinCount=1|ComponentKindVersion2=5
|RECORD=2|OwnerIndex=1187|OwnerPartId=1|FormalType=1|Electrical=4|PinConglomerate=32|PinLength=20|Location.X=680|Location.Y=400|Name=1|Designator=1|SwapIDPart=Ž&Ž||PinPropagationDelay=0.000000E+000
|RECORD=8|OwnerIndex=1187|IsNotAccesible=T|IndexInSheet=1|OwnerPartId=1|Location.X=670|Location.Y=400|Radius=5|SecondaryRadius=5|LineWidth=1|AreaColor=255
|RECORD=6|OwnerIndex=1187|IsNotAccesible=T|IndexInSheet=2|OwnerPartId=1|LineWidth=1|LocationCount=2|X1=680|Y1=400|X2=675|Y2=400
|RECORD=41|OwnerIndex=1187|IndexInSheet=3|OwnerPartId=-1|Location.X=665|Location.Y=405|Color=8388608|FontID=1|IsHidden=T|Name=Internal Part Number
|RECORD=41|OwnerIndex=1187|IndexInSheet=4|OwnerPartId=-1|Location.X=665|Location.Y=405|Color=8388608|FontID=1|IsHidden=T|Name=Pitch
|RECORD=41|OwnerIndex=1187|IndexInSheet=5|OwnerPartId=-1|Location.X=665|Location.Y=405|Color=8388608|FontID=1|IsHidden=T|Name=Color
|RECORD=41|OwnerIndex=1187|IndexInSheet=6|OwnerPartId=-1|Location.X=665|Location.Y=405|Color=8388608|FontID=1|IsHidden=T|Name=Min Operating Temperature
|RECORD=41|OwnerIndex=1187|IndexInSheet=7|OwnerPartId=-1|Location.X=665|Location.Y=405|Color=8388608|FontID=1|IsHidden=T|Name=Manufacturer Part Number
|RECORD=41|OwnerIndex=1187|IndexInSheet=8|OwnerPartId=-1|Location.X=665|Location.Y=405|Color=8388608|FontID=1|IsHidden=T|Name=Max Operating Temperature
|RECORD=41|OwnerIndex=1187|IndexInSheet=9|OwnerPartId=-1|Location.X=665|Location.Y=405|Color=8388608|FontID=1|IsHidden=T|Name=Supplier 1
|RECORD=41|OwnerIndex=1187|IndexInSheet=10|OwnerPartId=-1|Location.X=665|Location.Y=405|Color=8388608|FontID=1|IsHidden=T|Name=Material - Body
|RECORD=41|OwnerIndex=1187|IndexInSheet=11|OwnerPartId=-1|Location.X=665|Location.Y=405|Color=8388608|FontID=1|IsHidden=T|Name=Material - Insulation
|RECORD=41|OwnerIndex=1187|IndexInSheet=12|OwnerPartId=-1|Location.X=665|Location.Y=405|Color=8388608|FontID=1|IsHidden=T|Name=RoHS
|RECORD=41|OwnerIndex=1187|IndexInSheet=13|OwnerPartId=-1|Location.X=665|Location.Y=405|Color=8388608|FontID=1|IsHidden=T|Name=Plating
|RECORD=41|OwnerIndex=1187|IndexInSheet=14|OwnerPartId=-1|Location.X=665|Location.Y=405|Color=8388608|FontID=1|IsHidden=T|Text=PC Test Point, Surface Mount|Name=Type
|RECORD=41|OwnerIndex=1187|IndexInSheet=15|OwnerPartId=-1|Location.X=665|Location.Y=405|Color=8388608|FontID=1|IsHidden=T|Name=Manufacturer
|RECORD=41|OwnerIndex=1187|IndexInSheet=16|OwnerPartId=-1|Location.X=665|Location.Y=405|Color=8388608|FontID=1|IsHidden=T|Name=Datasheet URL
|RECORD=41|OwnerIndex=1187|IndexInSheet=17|OwnerPartId=-1|Location.X=665|Location.Y=405|Color=8388608|FontID=1|IsHidden=T|Name=Height
|RECORD=41|OwnerIndex=1187|IndexInSheet=18|OwnerPartId=-1|Location.X=665|Location.Y=405|Color=8388608|FontID=1|IsHidden=T|Text=1.00mm Dia Pad|Name=Size / Dimension
|RECORD=41|OwnerIndex=1187|IndexInSheet=19|OwnerPartId=-1|Location.X=665|Location.Y=405|Color=8388608|FontID=1|IsHidden=T|Name=Part Status
|RECORD=41|OwnerIndex=1187|IndexInSheet=20|OwnerPartId=-1|Location.X=665|Location.Y=405|Color=8388608|FontID=1|IsHidden=T|Name=Supplier Part Number 1
|RECORD=41|OwnerIndex=1187|IndexInSheet=21|OwnerPartId=-1|Location.X=665|Location.Y=405|Color=8388608|FontID=1|IsHidden=T|Text=Test Points|Name=Category
|RECORD=41|OwnerIndex=1187|IndexInSheet=22|OwnerPartId=-1|Location.X=665|Location.Y=405|Color=8388608|FontID=1|IsHidden=T|Text=1.00mm Dia Pad|Name=Mounting Type
|RECORD=41|OwnerIndex=1187|IndexInSheet=23|OwnerPartId=-1|Location.X=665|Location.Y=405|Color=8388608|FontID=1|IsHidden=T|Name=Series
|RECORD=34|OwnerIndex=1187|IndexInSheet=-1|OwnerPartId=-1|Location.X=650|Location.Y=400|Color=8388608|FontID=1|Text=TP3|Name=Designator|ReadOnlyState=1
|RECORD=41|OwnerIndex=1187|IndexInSheet=-1|OwnerPartId=-1|Location.X=665|Location.Y=405|Color=8388608|FontID=1|IsHidden=T|Text=SMT_100DIA|Name=Comment
|RECORD=44|OwnerIndex=1187
|RECORD=45|OwnerIndex=1215|IndexInSheet=-1|Description=Test Point, 1pin, Surface Mount 1.00mm Diameter|UseComponentLibrary=T|ModelName=TP001V_SMT_100DIA|ModelType=PCBLIB|DatafileCount=1|ModelDatafileEntity0=TP001V_SMT_100DIA|ModelDatafileKind0=PCBLib|IsCurrent=T|DatalinksLocked=T|DatabaseDatalinksLocked=T
|RECORD=46|OwnerIndex=1216
|RECORD=48|OwnerIndex=1216
|RECORD=41|OwnerIndex=1218|IndexInSheet=-1|OwnerPartId=-1|Color=8388608|FontID=1|IsHidden=T|Text=2D|Name=Available Preview Images
|RECORD=1|LibReference=TP_NoColor_001pin_No_BOM|ComponentDescription=TEST POINT, PC, SMT, 1.00MM DIA|PartCount=2|DisplayModeCount=1|IndexInSheet=80|OwnerPartId=-1|Location.X=660|Location.Y=360|CurrentPartId=1|LibraryPath=*|SourceLibraryName=RL Research Altium Server|TargetFileName=*|AreaColor=11599871|Color=128|PartIDLocked=T|DesignItemId=TPS-CMP-00004-3|AllPinCount=1|ComponentKindVersion2=5
|RECORD=2|OwnerIndex=1220|OwnerPartId=1|FormalType=1|Electrical=4|PinConglomerate=32|PinLength=20|Location.X=680|Location.Y=350|Name=1|Designator=1|SwapIDPart=Ž&Ž||PinPropagationDelay=0.000000E+000
|RECORD=8|OwnerIndex=1220|IsNotAccesible=T|IndexInSheet=1|OwnerPartId=1|Location.X=670|Location.Y=350|Radius=5|SecondaryRadius=5|LineWidth=1|AreaColor=255
|RECORD=6|OwnerIndex=1220|IsNotAccesible=T|IndexInSheet=2|OwnerPartId=1|LineWidth=1|LocationCount=2|X1=680|Y1=350|X2=675|Y2=350
|RECORD=41|OwnerIndex=1220|IndexInSheet=3|OwnerPartId=-1|Location.X=665|Location.Y=355|Color=8388608|FontID=1|IsHidden=T|Name=Internal Part Number
|RECORD=41|OwnerIndex=1220|IndexInSheet=4|OwnerPartId=-1|Location.X=665|Location.Y=355|Color=8388608|FontID=1|IsHidden=T|Name=Pitch
|RECORD=41|OwnerIndex=1220|IndexInSheet=5|OwnerPartId=-1|Location.X=665|Location.Y=355|Color=8388608|FontID=1|IsHidden=T|Name=Color
|RECORD=41|OwnerIndex=1220|IndexInSheet=6|OwnerPartId=-1|Location.X=665|Location.Y=355|Color=8388608|FontID=1|IsHidden=T|Name=Min Operating Temperature
|RECORD=41|OwnerIndex=1220|IndexInSheet=7|OwnerPartId=-1|Location.X=665|Location.Y=355|Color=8388608|FontID=1|IsHidden=T|Name=Manufacturer Part Number
|RECORD=41|OwnerIndex=1220|IndexInSheet=8|OwnerPartId=-1|Location.X=665|Location.Y=355|Color=8388608|FontID=1|IsHidden=T|Name=Max Operating Temperature
|RECORD=41|OwnerIndex=1220|IndexInSheet=9|OwnerPartId=-1|Location.X=665|Location.Y=355|Color=8388608|FontID=1|IsHidden=T|Name=Supplier 1
|RECORD=41|OwnerIndex=1220|IndexInSheet=10|OwnerPartId=-1|Location.X=665|Location.Y=355|Color=8388608|FontID=1|IsHidden=T|Name=Material - Body
|RECORD=41|OwnerIndex=1220|IndexInSheet=11|OwnerPartId=-1|Location.X=665|Location.Y=355|Color=8388608|FontID=1|IsHidden=T|Name=Material - Insulation
|RECORD=41|OwnerIndex=1220|IndexInSheet=12|OwnerPartId=-1|Location.X=665|Location.Y=355|Color=8388608|FontID=1|IsHidden=T|Name=RoHS
|RECORD=41|OwnerIndex=1220|IndexInSheet=13|OwnerPartId=-1|Location.X=665|Location.Y=355|Color=8388608|FontID=1|IsHidden=T|Name=Plating
|RECORD=41|OwnerIndex=1220|IndexInSheet=14|OwnerPartId=-1|Location.X=665|Location.Y=355|Color=8388608|FontID=1|IsHidden=T|Text=PC Test Point, Surface Mount|Name=Type
|RECORD=41|OwnerIndex=1220|IndexInSheet=15|OwnerPartId=-1|Location.X=665|Location.Y=355|Color=8388608|FontID=1|IsHidden=T|Name=Manufacturer
|RECORD=41|OwnerIndex=1220|IndexInSheet=16|OwnerPartId=-1|Location.X=665|Location.Y=355|Color=8388608|FontID=1|IsHidden=T|Name=Datasheet URL
|RECORD=41|OwnerIndex=1220|IndexInSheet=17|OwnerPartId=-1|Location.X=665|Location.Y=355|Color=8388608|FontID=1|IsHidden=T|Name=Height
|RECORD=41|OwnerIndex=1220|IndexInSheet=18|OwnerPartId=-1|Location.X=665|Location.Y=355|Color=8388608|FontID=1|IsHidden=T|Text=1.00mm Dia Pad|Name=Size / Dimension
|RECORD=41|OwnerIndex=1220|IndexInSheet=19|OwnerPartId=-1|Location.X=665|Location.Y=355|Color=8388608|FontID=1|IsHidden=T|Name=Part Status
|RECORD=41|OwnerIndex=1220|IndexInSheet=20|OwnerPartId=-1|Location.X=665|Location.Y=355|Color=8388608|FontID=1|IsHidden=T|Name=Supplier Part Number 1
|RECORD=41|OwnerIndex=1220|IndexInSheet=21|OwnerPartId=-1|Location.X=665|Location.Y=355|Color=8388608|FontID=1|IsHidden=T|Text=Test Points|Name=Category
|RECORD=41|OwnerIndex=1220|IndexInSheet=22|OwnerPartId=-1|Location.X=665|Location.Y=355|Color=8388608|FontID=1|IsHidden=T|Text=1.00mm Dia Pad|Name=Mounting Type
|RECORD=41|OwnerIndex=1220|IndexInSheet=23|OwnerPartId=-1|Location.X=665|Location.Y=355|Color=8388608|FontID=1|IsHidden=T|Name=Series
|RECORD=34|OwnerIndex=1220|IndexInSheet=-1|OwnerPartId=-1|Location.X=650|Location.Y=350|Color=8388608|FontID=1|Text=TP5|Name=Designator|ReadOnlyState=1
|RECORD=41|OwnerIndex=1220|IndexInSheet=-1|OwnerPartId=-1|Location.X=665|Location.Y=355|Color=8388608|FontID=1|IsHidden=T|Text=SMT_100DIA|Name=Comment
|RECORD=44|OwnerIndex=1220
|RECORD=45|OwnerIndex=1248|IndexInSheet=-1|Description=Test Point, 1pin, Surface Mount 1.00mm Diameter|UseComponentLibrary=T|ModelName=TP001V_SMT_100DIA|ModelType=PCBLIB|DatafileCount=1|ModelDatafileEntity0=TP001V_SMT_100DIA|ModelDatafileKind0=PCBLib|IsCurrent=T|DatalinksLocked=T|DatabaseDatalinksLocked=T
|RECORD=46|OwnerIndex=1249
|RECORD=48|OwnerIndex=1249
|RECORD=41|OwnerIndex=1251|IndexInSheet=-1|OwnerPartId=-1|Color=8388608|FontID=1|IsHidden=T|Text=2D|Name=Available Preview Images
|RECORD=1|LibReference=TP_NoColor_001pin_No_BOM|ComponentDescription=TEST POINT, PC, SMT, 1.00MM DIA|PartCount=2|DisplayModeCount=1|IndexInSheet=81|OwnerPartId=-1|Location.X=660|Location.Y=370|CurrentPartId=1|LibraryPath=*|SourceLibraryName=RL Research Altium Server|TargetFileName=*|AreaColor=11599871|Color=128|PartIDLocked=T|DesignItemId=TPS-CMP-00004-3|AllPinCount=1|ComponentKindVersion2=5
|RECORD=2|OwnerIndex=1253|OwnerPartId=1|FormalType=1|Electrical=4|PinConglomerate=32|PinLength=20|Location.X=680|Location.Y=360|Name=1|Designator=1|SwapIDPart=Ž&Ž||PinPropagationDelay=0.000000E+000
|RECORD=8|OwnerIndex=1253|IsNotAccesible=T|IndexInSheet=1|OwnerPartId=1|Location.X=670|Location.Y=360|Radius=5|SecondaryRadius=5|LineWidth=1|AreaColor=255
|RECORD=6|OwnerIndex=1253|IsNotAccesible=T|IndexInSheet=2|OwnerPartId=1|LineWidth=1|LocationCount=2|X1=680|Y1=360|X2=675|Y2=360
|RECORD=41|OwnerIndex=1253|IndexInSheet=3|OwnerPartId=-1|Location.X=665|Location.Y=365|Color=8388608|FontID=1|IsHidden=T|Name=Internal Part Number
|RECORD=41|OwnerIndex=1253|IndexInSheet=4|OwnerPartId=-1|Location.X=665|Location.Y=365|Color=8388608|FontID=1|IsHidden=T|Name=Pitch
|RECORD=41|OwnerIndex=1253|IndexInSheet=5|OwnerPartId=-1|Location.X=665|Location.Y=365|Color=8388608|FontID=1|IsHidden=T|Name=Color
|RECORD=41|OwnerIndex=1253|IndexInSheet=6|OwnerPartId=-1|Location.X=665|Location.Y=365|Color=8388608|FontID=1|IsHidden=T|Name=Min Operating Temperature
|RECORD=41|OwnerIndex=1253|IndexInSheet=7|OwnerPartId=-1|Location.X=665|Location.Y=365|Color=8388608|FontID=1|IsHidden=T|Name=Manufacturer Part Number
|RECORD=41|OwnerIndex=1253|IndexInSheet=8|OwnerPartId=-1|Location.X=665|Location.Y=365|Color=8388608|FontID=1|IsHidden=T|Name=Max Operating Temperature
|RECORD=41|OwnerIndex=1253|IndexInSheet=9|OwnerPartId=-1|Location.X=665|Location.Y=365|Color=8388608|FontID=1|IsHidden=T|Name=Supplier 1
|RECORD=41|OwnerIndex=1253|IndexInSheet=10|OwnerPartId=-1|Location.X=665|Location.Y=365|Color=8388608|FontID=1|IsHidden=T|Name=Material - Body
|RECORD=41|OwnerIndex=1253|IndexInSheet=11|OwnerPartId=-1|Location.X=665|Location.Y=365|Color=8388608|FontID=1|IsHidden=T|Name=Material - Insulation
|RECORD=41|OwnerIndex=1253|IndexInSheet=12|OwnerPartId=-1|Location.X=665|Location.Y=365|Color=8388608|FontID=1|IsHidden=T|Name=RoHS
|RECORD=41|OwnerIndex=1253|IndexInSheet=13|OwnerPartId=-1|Location.X=665|Location.Y=365|Color=8388608|FontID=1|IsHidden=T|Name=Plating
|RECORD=41|OwnerIndex=1253|IndexInSheet=14|OwnerPartId=-1|Location.X=665|Location.Y=365|Color=8388608|FontID=1|IsHidden=T|Text=PC Test Point, Surface Mount|Name=Type
|RECORD=41|OwnerIndex=1253|IndexInSheet=15|OwnerPartId=-1|Location.X=665|Location.Y=365|Color=8388608|FontID=1|IsHidden=T|Name=Manufacturer
|RECORD=41|OwnerIndex=1253|IndexInSheet=16|OwnerPartId=-1|Location.X=665|Location.Y=365|Color=8388608|FontID=1|IsHidden=T|Name=Datasheet URL
|RECORD=41|OwnerIndex=1253|IndexInSheet=17|OwnerPartId=-1|Location.X=665|Location.Y=365|Color=8388608|FontID=1|IsHidden=T|Name=Height
|RECORD=41|OwnerIndex=1253|IndexInSheet=18|OwnerPartId=-1|Location.X=665|Location.Y=365|Color=8388608|FontID=1|IsHidden=T|Text=1.00mm Dia Pad|Name=Size / Dimension
|RECORD=41|OwnerIndex=1253|IndexInSheet=19|OwnerPartId=-1|Location.X=665|Location.Y=365|Color=8388608|FontID=1|IsHidden=T|Name=Part Status
|RECORD=41|OwnerIndex=1253|IndexInSheet=20|OwnerPartId=-1|Location.X=665|Location.Y=365|Color=8388608|FontID=1|IsHidden=T|Name=Supplier Part Number 1
|RECORD=41|OwnerIndex=1253|IndexInSheet=21|OwnerPartId=-1|Location.X=665|Location.Y=365|Color=8388608|FontID=1|IsHidden=T|Text=Test Points|Name=Category
|RECORD=41|OwnerIndex=1253|IndexInSheet=22|OwnerPartId=-1|Location.X=665|Location.Y=365|Color=8388608|FontID=1|IsHidden=T|Text=1.00mm Dia Pad|Name=Mounting Type
|RECORD=41|OwnerIndex=1253|IndexInSheet=23|OwnerPartId=-1|Location.X=665|Location.Y=365|Color=8388608|FontID=1|IsHidden=T|Name=Series
|RECORD=34|OwnerIndex=1253|IndexInSheet=-1|OwnerPartId=-1|Location.X=650|Location.Y=360|Color=8388608|FontID=1|Text=TP4|Name=Designator|ReadOnlyState=1
|RECORD=41|OwnerIndex=1253|IndexInSheet=-1|OwnerPartId=-1|Location.X=665|Location.Y=365|Color=8388608|FontID=1|IsHidden=T|Text=SMT_100DIA|Name=Comment
|RECORD=44|OwnerIndex=1253
|RECORD=45|OwnerIndex=1281|IndexInSheet=-1|Description=Test Point, 1pin, Surface Mount 1.00mm Diameter|UseComponentLibrary=T|ModelName=TP001V_SMT_100DIA|ModelType=PCBLIB|DatafileCount=1|ModelDatafileEntity0=TP001V_SMT_100DIA|ModelDatafileKind0=PCBLib|IsCurrent=T|DatalinksLocked=T|DatabaseDatalinksLocked=T
|RECORD=46|OwnerIndex=1282
|RECORD=48|OwnerIndex=1282
|RECORD=41|OwnerIndex=1284|IndexInSheet=-1|OwnerPartId=-1|Color=8388608|FontID=1|IsHidden=T|Text=2D|Name=Available Preview Images
|RECORD=1|LibReference=TP_NoColor_001pin_No_BOM|ComponentDescription=TEST POINT, PC, SMT, 1.00MM DIA|PartCount=2|DisplayModeCount=1|IndexInSheet=82|OwnerPartId=-1|Location.X=660|Location.Y=340|CurrentPartId=1|LibraryPath=*|SourceLibraryName=RL Research Altium Server|TargetFileName=*|AreaColor=11599871|Color=128|PartIDLocked=T|DesignItemId=TPS-CMP-00004-3|AllPinCount=1|ComponentKindVersion2=5
|RECORD=2|OwnerIndex=1286|OwnerPartId=1|FormalType=1|Electrical=4|PinConglomerate=32|PinLength=20|Location.X=680|Location.Y=330|Name=1|Designator=1|SwapIDPart=Ž&Ž||PinPropagationDelay=0.000000E+000
|RECORD=8|OwnerIndex=1286|IsNotAccesible=T|IndexInSheet=1|OwnerPartId=1|Location.X=670|Location.Y=330|Radius=5|SecondaryRadius=5|LineWidth=1|AreaColor=255
|RECORD=6|OwnerIndex=1286|IsNotAccesible=T|IndexInSheet=2|OwnerPartId=1|LineWidth=1|LocationCount=2|X1=680|Y1=330|X2=675|Y2=330
|RECORD=41|OwnerIndex=1286|IndexInSheet=3|OwnerPartId=-1|Location.X=665|Location.Y=335|Color=8388608|FontID=1|IsHidden=T|Name=Internal Part Number
|RECORD=41|OwnerIndex=1286|IndexInSheet=4|OwnerPartId=-1|Location.X=665|Location.Y=335|Color=8388608|FontID=1|IsHidden=T|Name=Pitch
|RECORD=41|OwnerIndex=1286|IndexInSheet=5|OwnerPartId=-1|Location.X=665|Location.Y=335|Color=8388608|FontID=1|IsHidden=T|Name=Color
|RECORD=41|OwnerIndex=1286|IndexInSheet=6|OwnerPartId=-1|Location.X=665|Location.Y=335|Color=8388608|FontID=1|IsHidden=T|Name=Min Operating Temperature
|RECORD=41|OwnerIndex=1286|IndexInSheet=7|OwnerPartId=-1|Location.X=665|Location.Y=335|Color=8388608|FontID=1|IsHidden=T|Name=Manufacturer Part Number
|RECORD=41|OwnerIndex=1286|IndexInSheet=8|OwnerPartId=-1|Location.X=665|Location.Y=335|Color=8388608|FontID=1|IsHidden=T|Name=Max Operating Temperature
|RECORD=41|OwnerIndex=1286|IndexInSheet=9|OwnerPartId=-1|Location.X=665|Location.Y=335|Color=8388608|FontID=1|IsHidden=T|Name=Supplier 1
|RECORD=41|OwnerIndex=1286|IndexInSheet=10|OwnerPartId=-1|Location.X=665|Location.Y=335|Color=8388608|FontID=1|IsHidden=T|Name=Material - Body
|RECORD=41|OwnerIndex=1286|IndexInSheet=11|OwnerPartId=-1|Location.X=665|Location.Y=335|Color=8388608|FontID=1|IsHidden=T|Name=Material - Insulation
|RECORD=41|OwnerIndex=1286|IndexInSheet=12|OwnerPartId=-1|Location.X=665|Location.Y=335|Color=8388608|FontID=1|IsHidden=T|Name=RoHS
|RECORD=41|OwnerIndex=1286|IndexInSheet=13|OwnerPartId=-1|Location.X=665|Location.Y=335|Color=8388608|FontID=1|IsHidden=T|Name=Plating
|RECORD=41|OwnerIndex=1286|IndexInSheet=14|OwnerPartId=-1|Location.X=665|Location.Y=335|Color=8388608|FontID=1|IsHidden=T|Text=PC Test Point, Surface Mount|Name=Type
|RECORD=41|OwnerIndex=1286|IndexInSheet=15|OwnerPartId=-1|Location.X=665|Location.Y=335|Color=8388608|FontID=1|IsHidden=T|Name=Manufacturer
|RECORD=41|OwnerIndex=1286|IndexInSheet=16|OwnerPartId=-1|Location.X=665|Location.Y=335|Color=8388608|FontID=1|IsHidden=T|Name=Datasheet URL
|RECORD=41|OwnerIndex=1286|IndexInSheet=17|OwnerPartId=-1|Location.X=665|Location.Y=335|Color=8388608|FontID=1|IsHidden=T|Name=Height
|RECORD=41|OwnerIndex=1286|IndexInSheet=18|OwnerPartId=-1|Location.X=665|Location.Y=335|Color=8388608|FontID=1|IsHidden=T|Text=1.00mm Dia Pad|Name=Size / Dimension
|RECORD=41|OwnerIndex=1286|IndexInSheet=19|OwnerPartId=-1|Location.X=665|Location.Y=335|Color=8388608|FontID=1|IsHidden=T|Name=Part Status
|RECORD=41|OwnerIndex=1286|IndexInSheet=20|OwnerPartId=-1|Location.X=665|Location.Y=335|Color=8388608|FontID=1|IsHidden=T|Name=Supplier Part Number 1
|RECORD=41|OwnerIndex=1286|IndexInSheet=21|OwnerPartId=-1|Location.X=665|Location.Y=335|Color=8388608|FontID=1|IsHidden=T|Text=Test Points|Name=Category
|RECORD=41|OwnerIndex=1286|IndexInSheet=22|OwnerPartId=-1|Location.X=665|Location.Y=335|Color=8388608|FontID=1|IsHidden=T|Text=1.00mm Dia Pad|Name=Mounting Type
|RECORD=41|OwnerIndex=1286|IndexInSheet=23|OwnerPartId=-1|Location.X=665|Location.Y=335|Color=8388608|FontID=1|IsHidden=T|Name=Series
|RECORD=34|OwnerIndex=1286|IndexInSheet=-1|OwnerPartId=-1|Location.X=650|Location.Y=330|Color=8388608|FontID=1|Text=TP6|Name=Designator|ReadOnlyState=1
|RECORD=41|OwnerIndex=1286|IndexInSheet=-1|OwnerPartId=-1|Location.X=665|Location.Y=335|Color=8388608|FontID=1|IsHidden=T|Text=SMT_100DIA|Name=Comment
|RECORD=44|OwnerIndex=1286
|RECORD=45|OwnerIndex=1314|IndexInSheet=-1|Description=Test Point, 1pin, Surface Mount 1.00mm Diameter|UseComponentLibrary=T|ModelName=TP001V_SMT_100DIA|ModelType=PCBLIB|DatafileCount=1|ModelDatafileEntity0=TP001V_SMT_100DIA|ModelDatafileKind0=PCBLib|IsCurrent=T|DatalinksLocked=T|DatabaseDatalinksLocked=T
|RECORD=46|OwnerIndex=1315
|RECORD=48|OwnerIndex=1315
|RECORD=41|OwnerIndex=1317|IndexInSheet=-1|OwnerPartId=-1|Color=8388608|FontID=1|IsHidden=T|Text=2D|Name=Available Preview Images
|RECORD=1|LibReference=TP_NoColor_001pin_No_BOM|ComponentDescription=TEST POINT, PC, SMT, 1.00MM DIA|PartCount=2|DisplayModeCount=1|IndexInSheet=83|OwnerPartId=-1|Location.X=660|Location.Y=330|CurrentPartId=1|LibraryPath=*|SourceLibraryName=RL Research Altium Server|TargetFileName=*|AreaColor=11599871|Color=128|PartIDLocked=T|DesignItemId=TPS-CMP-00004-3|AllPinCount=1|ComponentKindVersion2=5
|RECORD=2|OwnerIndex=1319|OwnerPartId=1|FormalType=1|Electrical=4|PinConglomerate=32|PinLength=20|Location.X=680|Location.Y=320|Name=1|Designator=1|SwapIDPart=Ž&Ž||PinPropagationDelay=0.000000E+000
|RECORD=8|OwnerIndex=1319|IsNotAccesible=T|IndexInSheet=1|OwnerPartId=1|Location.X=670|Location.Y=320|Radius=5|SecondaryRadius=5|LineWidth=1|AreaColor=255
|RECORD=6|OwnerIndex=1319|IsNotAccesible=T|IndexInSheet=2|OwnerPartId=1|LineWidth=1|LocationCount=2|X1=680|Y1=320|X2=675|Y2=320
|RECORD=41|OwnerIndex=1319|IndexInSheet=3|OwnerPartId=-1|Location.X=665|Location.Y=325|Color=8388608|FontID=1|IsHidden=T|Name=Internal Part Number
|RECORD=41|OwnerIndex=1319|IndexInSheet=4|OwnerPartId=-1|Location.X=665|Location.Y=325|Color=8388608|FontID=1|IsHidden=T|Name=Pitch
|RECORD=41|OwnerIndex=1319|IndexInSheet=5|OwnerPartId=-1|Location.X=665|Location.Y=325|Color=8388608|FontID=1|IsHidden=T|Name=Color
|RECORD=41|OwnerIndex=1319|IndexInSheet=6|OwnerPartId=-1|Location.X=665|Location.Y=325|Color=8388608|FontID=1|IsHidden=T|Name=Min Operating Temperature
|RECORD=41|OwnerIndex=1319|IndexInSheet=7|OwnerPartId=-1|Location.X=665|Location.Y=325|Color=8388608|FontID=1|IsHidden=T|Name=Manufacturer Part Number
|RECORD=41|OwnerIndex=1319|IndexInSheet=8|OwnerPartId=-1|Location.X=665|Location.Y=325|Color=8388608|FontID=1|IsHidden=T|Name=Max Operating Temperature
|RECORD=41|OwnerIndex=1319|IndexInSheet=9|OwnerPartId=-1|Location.X=665|Location.Y=325|Color=8388608|FontID=1|IsHidden=T|Name=Supplier 1
|RECORD=41|OwnerIndex=1319|IndexInSheet=10|OwnerPartId=-1|Location.X=665|Location.Y=325|Color=8388608|FontID=1|IsHidden=T|Name=Material - Body
|RECORD=41|OwnerIndex=1319|IndexInSheet=11|OwnerPartId=-1|Location.X=665|Location.Y=325|Color=8388608|FontID=1|IsHidden=T|Name=Material - Insulation
|RECORD=41|OwnerIndex=1319|IndexInSheet=12|OwnerPartId=-1|Location.X=665|Location.Y=325|Color=8388608|FontID=1|IsHidden=T|Name=RoHS
|RECORD=41|OwnerIndex=1319|IndexInSheet=13|OwnerPartId=-1|Location.X=665|Location.Y=325|Color=8388608|FontID=1|IsHidden=T|Name=Plating
|RECORD=41|OwnerIndex=1319|IndexInSheet=14|OwnerPartId=-1|Location.X=665|Location.Y=325|Color=8388608|FontID=1|IsHidden=T|Text=PC Test Point, Surface Mount|Name=Type
|RECORD=41|OwnerIndex=1319|IndexInSheet=15|OwnerPartId=-1|Location.X=665|Location.Y=325|Color=8388608|FontID=1|IsHidden=T|Name=Manufacturer
|RECORD=41|OwnerIndex=1319|IndexInSheet=16|OwnerPartId=-1|Location.X=665|Location.Y=325|Color=8388608|FontID=1|IsHidden=T|Name=Datasheet URL
|RECORD=41|OwnerIndex=1319|IndexInSheet=17|OwnerPartId=-1|Location.X=665|Location.Y=325|Color=8388608|FontID=1|IsHidden=T|Name=Height
|RECORD=41|OwnerIndex=1319|IndexInSheet=18|OwnerPartId=-1|Location.X=665|Location.Y=325|Color=8388608|FontID=1|IsHidden=T|Text=1.00mm Dia Pad|Name=Size / Dimension
|RECORD=41|OwnerIndex=1319|IndexInSheet=19|OwnerPartId=-1|Location.X=665|Location.Y=325|Color=8388608|FontID=1|IsHidden=T|Name=Part Status
|RECORD=41|OwnerIndex=1319|IndexInSheet=20|OwnerPartId=-1|Location.X=665|Location.Y=325|Color=8388608|FontID=1|IsHidden=T|Name=Supplier Part Number 1
|RECORD=41|OwnerIndex=1319|IndexInSheet=21|OwnerPartId=-1|Location.X=665|Location.Y=325|Color=8388608|FontID=1|IsHidden=T|Text=Test Points|Name=Category
|RECORD=41|OwnerIndex=1319|IndexInSheet=22|OwnerPartId=-1|Location.X=665|Location.Y=325|Color=8388608|FontID=1|IsHidden=T|Text=1.00mm Dia Pad|Name=Mounting Type
|RECORD=41|OwnerIndex=1319|IndexInSheet=23|OwnerPartId=-1|Location.X=665|Location.Y=325|Color=8388608|FontID=1|IsHidden=T|Name=Series
|RECORD=34|OwnerIndex=1319|IndexInSheet=-1|OwnerPartId=-1|Location.X=650|Location.Y=320|Color=8388608|FontID=1|Text=TP7|Name=Designator|ReadOnlyState=1
|RECORD=41|OwnerIndex=1319|IndexInSheet=-1|OwnerPartId=-1|Location.X=665|Location.Y=325|Color=8388608|FontID=1|IsHidden=T|Text=SMT_100DIA|Name=Comment
|RECORD=44|OwnerIndex=1319
|RECORD=45|OwnerIndex=1347|IndexInSheet=-1|Description=Test Point, 1pin, Surface Mount 1.00mm Diameter|UseComponentLibrary=T|ModelName=TP001V_SMT_100DIA|ModelType=PCBLIB|DatafileCount=1|ModelDatafileEntity0=TP001V_SMT_100DIA|ModelDatafileKind0=PCBLib|IsCurrent=T|DatalinksLocked=T|DatabaseDatalinksLocked=T
|RECORD=46|OwnerIndex=1348
|RECORD=48|OwnerIndex=1348
|RECORD=41|OwnerIndex=1350|IndexInSheet=-1|OwnerPartId=-1|Color=8388608|FontID=1|IsHidden=T|Text=2D|Name=Available Preview Images
|RECORD=22|IndexInSheet=84|OwnerPartId=-1|Location.X=700|Location.Y=300|Color=255|Orientation=1|Symbol=Thin Cross|IsActive=T|SuppressAll=T
|RECORD=22|IndexInSheet=85|OwnerPartId=-1|Location.X=700|Location.Y=290|Color=255|Orientation=1|Symbol=Thin Cross|IsActive=T|SuppressAll=T
|RECORD=25|IndexInSheet=86|OwnerPartId=-1|Location.X=670|Location.Y=220|Color=128|FontID=1|Text=RF_IN
|RECORD=25|IndexInSheet=87|OwnerPartId=-1|Location.X=630|Location.Y=180|Color=128|FontID=1|Text=ANT_OFF
|RECORD=25|IndexInSheet=88|OwnerPartId=-1|Location.X=630|Location.Y=190|Color=128|FontID=1|Text=ANT_DET
|RECORD=25|IndexInSheet=89|OwnerPartId=-1|Location.X=630|Location.Y=170|Color=128|FontID=1|Text=ANT_SHORT_N
|RECORD=1|LibReference=TP_NoColor_001pin_No_BOM|ComponentDescription=TEST POINT, PC, SMT, 1.00MM DIA|PartCount=2|DisplayModeCount=1|IndexInSheet=90|OwnerPartId=-1|Location.X=870|Location.Y=140|Orientation=2|CurrentPartId=1|LibraryPath=*|SourceLibraryName=RL Research Altium Server|TargetFileName=*|AreaColor=11599871|Color=128|PartIDLocked=T|DesignItemId=TPS-CMP-00004-3|AllPinCount=1|ComponentKindVersion2=5
|RECORD=2|OwnerIndex=1358|OwnerPartId=1|FormalType=1|Electrical=4|PinConglomerate=34|PinLength=20|Location.X=850|Location.Y=150|Name=1|Designator=1|SwapIDPart=Ž&Ž||PinPropagationDelay=0.000000E+000
|RECORD=8|OwnerIndex=1358|IsNotAccesible=T|IndexInSheet=1|OwnerPartId=1|Location.X=860|Location.Y=150|Radius=5|SecondaryRadius=5|LineWidth=1|AreaColor=255
|RECORD=6|OwnerIndex=1358|IsNotAccesible=T|IndexInSheet=2|OwnerPartId=1|LineWidth=1|LocationCount=2|X1=850|Y1=150|X2=855|Y2=150
|RECORD=41|OwnerIndex=1358|IndexInSheet=3|OwnerPartId=-1|Location.X=828|Location.Y=155|Color=8388608|FontID=1|IsHidden=T|Name=Internal Part Number
|RECORD=41|OwnerIndex=1358|IndexInSheet=4|OwnerPartId=-1|Location.X=828|Location.Y=155|Color=8388608|FontID=1|IsHidden=T|Name=Pitch
|RECORD=41|OwnerIndex=1358|IndexInSheet=5|OwnerPartId=-1|Location.X=828|Location.Y=155|Color=8388608|FontID=1|IsHidden=T|Name=Color
|RECORD=41|OwnerIndex=1358|IndexInSheet=6|OwnerPartId=-1|Location.X=828|Location.Y=155|Color=8388608|FontID=1|IsHidden=T|Name=Min Operating Temperature
|RECORD=41|OwnerIndex=1358|IndexInSheet=7|OwnerPartId=-1|Location.X=828|Location.Y=155|Color=8388608|FontID=1|IsHidden=T|Name=Manufacturer Part Number
|RECORD=41|OwnerIndex=1358|IndexInSheet=8|OwnerPartId=-1|Location.X=828|Location.Y=155|Color=8388608|FontID=1|IsHidden=T|Name=Max Operating Temperature
|RECORD=41|OwnerIndex=1358|IndexInSheet=9|OwnerPartId=-1|Location.X=828|Location.Y=155|Color=8388608|FontID=1|IsHidden=T|Name=Supplier 1
|RECORD=41|OwnerIndex=1358|IndexInSheet=10|OwnerPartId=-1|Location.X=828|Location.Y=155|Color=8388608|FontID=1|IsHidden=T|Name=Material - Body
|RECORD=41|OwnerIndex=1358|IndexInSheet=11|OwnerPartId=-1|Location.X=828|Location.Y=155|Color=8388608|FontID=1|IsHidden=T|Name=Material - Insulation
|RECORD=41|OwnerIndex=1358|IndexInSheet=12|OwnerPartId=-1|Location.X=828|Location.Y=155|Color=8388608|FontID=1|IsHidden=T|Name=RoHS
|RECORD=41|OwnerIndex=1358|IndexInSheet=13|OwnerPartId=-1|Location.X=828|Location.Y=155|Color=8388608|FontID=1|IsHidden=T|Name=Plating
|RECORD=41|OwnerIndex=1358|IndexInSheet=14|OwnerPartId=-1|Location.X=828|Location.Y=155|Color=8388608|FontID=1|IsHidden=T|Text=PC Test Point, Surface Mount|Name=Type
|RECORD=41|OwnerIndex=1358|IndexInSheet=15|OwnerPartId=-1|Location.X=828|Location.Y=155|Color=8388608|FontID=1|IsHidden=T|Name=Manufacturer
|RECORD=41|OwnerIndex=1358|IndexInSheet=16|OwnerPartId=-1|Location.X=828|Location.Y=155|Color=8388608|FontID=1|IsHidden=T|Name=Datasheet URL
|RECORD=41|OwnerIndex=1358|IndexInSheet=17|OwnerPartId=-1|Location.X=828|Location.Y=155|Color=8388608|FontID=1|IsHidden=T|Name=Height
|RECORD=41|OwnerIndex=1358|IndexInSheet=18|OwnerPartId=-1|Location.X=828|Location.Y=155|Color=8388608|FontID=1|IsHidden=T|Text=1.00mm Dia Pad|Name=Size / Dimension
|RECORD=41|OwnerIndex=1358|IndexInSheet=19|OwnerPartId=-1|Location.X=828|Location.Y=155|Color=8388608|FontID=1|IsHidden=T|Name=Part Status
|RECORD=41|OwnerIndex=1358|IndexInSheet=20|OwnerPartId=-1|Location.X=828|Location.Y=155|Color=8388608|FontID=1|IsHidden=T|Name=Supplier Part Number 1
|RECORD=41|OwnerIndex=1358|IndexInSheet=21|OwnerPartId=-1|Location.X=828|Location.Y=155|Color=8388608|FontID=1|IsHidden=T|Text=Test Points|Name=Category
|RECORD=41|OwnerIndex=1358|IndexInSheet=22|OwnerPartId=-1|Location.X=828|Location.Y=155|Color=8388608|FontID=1|IsHidden=T|Text=1.00mm Dia Pad|Name=Mounting Type
|RECORD=41|OwnerIndex=1358|IndexInSheet=23|OwnerPartId=-1|Location.X=828|Location.Y=155|Color=8388608|FontID=1|IsHidden=T|Name=Series
|RECORD=34|OwnerIndex=1358|IndexInSheet=-1|OwnerPartId=-1|Location.X=849|Location.Y=135|Color=8388608|FontID=1|Text=TP8|Name=Designator|ReadOnlyState=1
|RECORD=41|OwnerIndex=1358|IndexInSheet=-1|OwnerPartId=-1|Location.X=828|Location.Y=155|Color=8388608|FontID=1|IsHidden=T|Text=SMT_100DIA|Name=Comment
|RECORD=44|OwnerIndex=1358
|RECORD=45|OwnerIndex=1386|IndexInSheet=-1|Description=Test Point, 1pin, Surface Mount 1.00mm Diameter|UseComponentLibrary=T|ModelName=TP001V_SMT_100DIA|ModelType=PCBLIB|DatafileCount=1|ModelDatafileEntity0=TP001V_SMT_100DIA|ModelDatafileKind0=PCBLib|IsCurrent=T|DatalinksLocked=T|DatabaseDatalinksLocked=T
|RECORD=46|OwnerIndex=1387
|RECORD=48|OwnerIndex=1387
|RECORD=41|OwnerIndex=1389|IndexInSheet=-1|OwnerPartId=-1|Color=8388608|FontID=1|IsHidden=T|Text=2D|Name=Available Preview Images
|RECORD=22|IndexInSheet=91|OwnerPartId=-1|Location.X=830|Location.Y=220|Color=255|Orientation=1|Symbol=Thin Cross|IsActive=T|SuppressAll=T
|RECORD=1|LibReference=LED_Green_300mil|ComponentDescription=LED, GREEN, 574NM, 20MA, 20MCD MIN, 2.5VF MAX, 0603, 1.10MM T|PartCount=2|DisplayModeCount=1|IndexInSheet=92|OwnerPartId=-1|Location.X=90|Location.Y=130|Orientation=2|CurrentPartId=1|LibraryPath=*|SourceLibraryName=RL Research Altium Server|TargetFileName=*|AreaColor=11599871|Color=128|PartIDLocked=T|DesignItemId=LED-CMP-00021-2|AllPinCount=2
|RECORD=2|OwnerIndex=1392|OwnerPartId=1|FormalType=1|Electrical=4|PinConglomerate=35|PinLength=10|Location.X=90|Location.Y=140|Name=Cathode|Designator=K|SwapIDPart=0|PinName_PositionConglomerate=16|Name_CustomFontID=16|PinDesignator_PositionConglomerate=16|Designator_CustomFontID=16|PinPropagationDelay=0.000000E+000
|RECORD=2|OwnerIndex=1392|OwnerPartId=1|FormalType=1|Electrical=4|PinConglomerate=33|PinLength=10|Location.X=90|Location.Y=150|Name=Anode|Designator=A|SwapIDPart=0|PinName_PositionConglomerate=16|Name_CustomFontID=16|PinDesignator_PositionConglomerate=16|Designator_CustomFontID=16|PinPropagationDelay=0.000000E+000
|RECORD=6|OwnerIndex=1392|IsNotAccesible=T|IndexInSheet=2|OwnerPartId=1|LineWidth=1|Color=65280|LocationCount=6|X1=84|Y1=144|X2=81|Y2=141|X3=80|Y3=142|X4=79|Y4=139|X5=82|Y5=140|X6=81|Y6=141
|RECORD=6|OwnerIndex=1392|IsNotAccesible=T|IndexInSheet=3|OwnerPartId=1|LineWidth=1|Color=65280|LocationCount=6|X1=83|Y1=148|X2=80|Y2=145|X3=79|Y3=146|X4=78|Y4=143|X5=81|Y5=144|X6=80|Y6=145
|RECORD=3|OwnerIndex=1392|IsNotAccesible=T|IndexInSheet=4|OwnerPartId=1|Symbol=33|Location.X=90|Location.Y=140|ScaleFactor=10|Orientation=3|LineWidth=1|Color=65280
|RECORD=6|OwnerIndex=1392|IsNotAccesible=T|IndexInSheet=5|OwnerPartId=1|LineWidth=1|Color=65280|LocationCount=2|X1=93|Y1=140|X2=87|Y2=140
|RECORD=6|OwnerIndex=1392|IsNotAccesible=T|IndexInSheet=6|OwnerPartId=1|LineWidth=1|Color=65280|LocationCount=2|X1=90|Y1=150|X2=90|Y2=146
|RECORD=41|OwnerIndex=1392|IndexInSheet=7|OwnerPartId=-1|Location.X=77|Location.Y=162|Color=8388608|FontID=1|IsHidden=T|Text=Clear|Name=Lens Transparency
|RECORD=41|OwnerIndex=1392|IndexInSheet=8|OwnerPartId=-1|Location.X=77|Location.Y=162|Color=8388608|FontID=1|IsHidden=T|Text=50mcd|Name=Millicandela Rating
|RECORD=41|OwnerIndex=1392|IndexInSheet=9|OwnerPartId=-1|Location.X=77|Location.Y=162|Color=8388608|FontID=1|IsHidden=T|Name=Type
|RECORD=41|OwnerIndex=1392|IndexInSheet=10|OwnerPartId=-1|Location.X=77|Location.Y=162|Color=8388608|FontID=1|IsHidden=T|Name=Wavelength
|RECORD=41|OwnerIndex=1392|IndexInSheet=11|OwnerPartId=-1|Location.X=77|Location.Y=162|Color=8388608|FontID=1|IsHidden=T|Text=2.2V|Name=Voltage - Forward (Vf) (Typ)
|RECORD=41|OwnerIndex=1392|IndexInSheet=12|OwnerPartId=-1|Location.X=77|Location.Y=162|Color=8388608|FontID=1|IsHidden=T|Text=1.60mm L x 0.80mm W|Name=Size / Dimension
|RECORD=41|OwnerIndex=1392|IndexInSheet=13|OwnerPartId=-1|Location.X=77|Location.Y=162|Color=8388608|FontID=1|IsHidden=T|Text=85°C|Name=Max Operating Temperature
|RECORD=41|OwnerIndex=1392|IndexInSheet=14|OwnerPartId=-1|Location.X=77|Location.Y=162|Color=8388608|FontID=1|IsHidden=T|Text=-40°C|Name=Min Operating Temperature
|RECORD=41|OwnerIndex=1392|IndexInSheet=15|OwnerPartId=-1|Location.X=77|Location.Y=162|Color=8388608|FontID=1|IsHidden=T|Name=Series
|RECORD=41|OwnerIndex=1392|IndexInSheet=16|OwnerPartId=-1|Location.X=77|Location.Y=162|Color=8388608|FontID=1|IsHidden=T|Name=Character Format
|RECORD=41|OwnerIndex=1392|IndexInSheet=17|OwnerPartId=-1|Location.X=77|Location.Y=162|Color=8388608|FontID=1|IsHidden=T|Name=Number of Characters
|RECORD=41|OwnerIndex=1392|IndexInSheet=18|OwnerPartId=-1|Location.X=77|Location.Y=162|Color=8388608|FontID=1|IsHidden=T|Text=Independent|Name=Configuration
|RECORD=41|OwnerIndex=1392|IndexInSheet=19|OwnerPartId=-1|Location.X=77|Location.Y=162|Color=8388608|FontID=1|IsHidden=T|Text=838-00422-00|Name=Internal Part Number
|RECORD=41|OwnerIndex=1392|IndexInSheet=20|OwnerPartId=-1|Location.X=77|Location.Y=162|Color=8388608|FontID=1|IsHidden=T|Name=Applications
|RECORD=41|OwnerIndex=1392|IndexInSheet=21|OwnerPartId=-1|Location.X=77|Location.Y=162|Color=8388608|FontID=1|IsHidden=T|Name=Connector Type
|RECORD=41|OwnerIndex=1392|IndexInSheet=22|OwnerPartId=-1|Location.X=77|Location.Y=162|Color=8388608|FontID=1|IsHidden=T|Name=Current - DC Forward (If) (Max)
|RECORD=41|OwnerIndex=1392|IndexInSheet=23|OwnerPartId=-1|Location.X=77|Location.Y=162|Color=8388608|FontID=1|IsHidden=T|Text=120°|Name=Viewing Angle
|RECORD=41|OwnerIndex=1392|IndexInSheet=24|OwnerPartId=-1|Location.X=77|Location.Y=162|Color=8388608|FontID=1|IsHidden=T|Name=Radiant Intensity (Ie) Min @ If
|RECORD=41|OwnerIndex=1392|IndexInSheet=25|OwnerPartId=-1|Location.X=77|Location.Y=162|Color=8388608|FontID=1|IsHidden=T|Text=LED Indication - Discrete|Name=Category
|RECORD=41|OwnerIndex=1392|IndexInSheet=26|OwnerPartId=-1|Location.X=77|Location.Y=162|Color=8388608|FontID=1|IsHidden=T|Name=Display Mode
|RECORD=41|OwnerIndex=1392|IndexInSheet=27|OwnerPartId=-1|Location.X=77|Location.Y=162|Color=8388608|FontID=1|IsHidden=T|Text=Green|Name=Lens Color
|RECORD=41|OwnerIndex=1392|IndexInSheet=28|OwnerPartId=-1|Location.X=77|Location.Y=162|Color=8388608|FontID=1|IsHidden=T|Text=0603 (1608 Metric)|Name=Case/Package
|RECORD=41|OwnerIndex=1392|IndexInSheet=29|OwnerPartId=-1|Location.X=77|Location.Y=162|Color=8388608|FontID=1|IsHidden=T|Name=Voltage - Supply
|RECORD=41|OwnerIndex=1392|IndexInSheet=30|OwnerPartId=-1|Location.X=77|Location.Y=162|Color=8388608|FontID=1|IsHidden=T|Text=20mA|Name=Current - Test
|RECORD=41|OwnerIndex=1392|IndexInSheet=31|OwnerPartId=-1|Location.X=77|Location.Y=162|Color=8388608|FontID=1|IsHidden=T|Name=Data Rate
|RECORD=41|OwnerIndex=1392|IndexInSheet=32|OwnerPartId=-1|Location.X=77|Location.Y=162|Color=8388608|FontID=1|IsHidden=T|Text=574nm|Name=Wavelength - Peak
|RECORD=41|OwnerIndex=1392|IndexInSheet=33|OwnerPartId=-1|Location.X=77|Location.Y=162|Color=8388608|FontID=1|IsHidden=T|Text=1.20mm x 0.80mm|Name=Lens Size
|RECORD=41|OwnerIndex=1392|IndexInSheet=34|OwnerPartId=-1|Location.X=77|Location.Y=162|Color=8388608|FontID=1|IsHidden=T|Name=Part Status
|RECORD=41|OwnerIndex=1392|IndexInSheet=35|OwnerPartId=-1|Location.X=77|Location.Y=162|Color=8388608|FontID=1|IsHidden=T|Text=Surface Mount|Name=Mounting Type
|RECORD=41|OwnerIndex=1392|IndexInSheet=36|OwnerPartId=-1|Location.X=77|Location.Y=162|Color=8388608|FontID=1|IsHidden=T|Text=Yes|Name=RoHS
|RECORD=41|OwnerIndex=1392|IndexInSheet=37|OwnerPartId=-1|Location.X=77|Location.Y=162|Color=8388608|FontID=1|IsHidden=T|Text=Lumex Opto/Components Inc.|Name=Manufacturer
|RECORD=41|OwnerIndex=1392|IndexInSheet=38|OwnerPartId=-1|Location.X=77|Location.Y=162|Color=8388608|FontID=1|IsHidden=T|Name=Wavelength - Dominant
|RECORD=41|OwnerIndex=1392|IndexInSheet=39|OwnerPartId=-1|Location.X=77|Location.Y=162|Color=8388608|FontID=1|IsHidden=T|Name=Features
|RECORD=41|OwnerIndex=1392|IndexInSheet=40|OwnerPartId=-1|Location.X=77|Location.Y=162|Color=8388608|FontID=1|IsHidden=T|Text=1.10mm|Name=Height (Max)
|RECORD=41|OwnerIndex=1392|IndexInSheet=41|OwnerPartId=-1|Location.X=77|Location.Y=162|Color=8388608|FontID=1|IsHidden=T|Text=Digikey|Name=Supplier 1
|RECORD=41|OwnerIndex=1392|IndexInSheet=42|OwnerPartId=-1|Location.X=77|Location.Y=162|Color=8388608|FontID=1|IsHidden=T|Name=Attenuation Value
|RECORD=41|OwnerIndex=1392|IndexInSheet=43|OwnerPartId=-1|Location.X=77|Location.Y=162|Color=8388608|FontID=1|IsHidden=T|Name=Display Format
|RECORD=41|OwnerIndex=1392|IndexInSheet=44|OwnerPartId=-1|Location.X=77|Location.Y=162|Color=8388608|FontID=1|IsHidden=T|Name=Current - Supply
|RECORD=41|OwnerIndex=1392|IndexInSheet=45|OwnerPartId=-1|Location.X=77|Location.Y=162|Color=8388608|FontID=1|IsHidden=T|Text=Rectangle with Flat Top|Name=Lens Style
|RECORD=41|OwnerIndex=1392|IndexInSheet=46|OwnerPartId=-1|Location.X=77|Location.Y=162|Color=8388608|FontID=1|IsHidden=T|Name=Viewing Area
|RECORD=41|OwnerIndex=1392|IndexInSheet=47|OwnerPartId=-1|Location.X=94|Location.Y=131|Color=8388608|FontID=1|Text=Green|Name=Color
|RECORD=41|OwnerIndex=1392|IndexInSheet=48|OwnerPartId=-1|Location.X=77|Location.Y=162|Color=8388608|FontID=2|IsHidden=T|Text=https://www.digikey.com/en/products/detail/lumex-opto-components-inc/SML-LXFM0603SUGCTR/7364547?s=N4IgTCBcDaIMoFkAyBaJANAYggDANhwGY4BVAcQGEAVAJRAF0BfIA|Name=Datasheet URL
|RECORD=41|OwnerIndex=1392|IndexInSheet=49|OwnerPartId=-1|Location.X=77|Location.Y=162|Color=8388608|FontID=1|IsHidden=T|Name=Orientation
|RECORD=41|OwnerIndex=1392|IndexInSheet=50|OwnerPartId=-1|Location.X=77|Location.Y=162|Color=8388608|FontID=1|IsHidden=T|Name=Display Type
|RECORD=41|OwnerIndex=1392|IndexInSheet=51|OwnerPartId=-1|Location.X=77|Location.Y=162|Color=8388608|FontID=1|IsHidden=T|Text=67-2320-1-ND|Name=Supplier Part Number 1
|RECORD=41|OwnerIndex=1392|IndexInSheet=52|OwnerPartId=-1|Location.X=77|Location.Y=162|Color=8388608|FontID=1|IsHidden=T|Text=SML-LXFM0603SUGCTR|Name=Manufacturer Part Number
|RECORD=41|OwnerIndex=1392|IndexInSheet=53|OwnerPartId=-1|Location.X=77|Location.Y=162|Color=8388608|FontID=1|IsHidden=T|Name=Backlight
|RECORD=34|OwnerIndex=1392|IndexInSheet=-1|OwnerPartId=-1|Location.X=94|Location.Y=141|Color=8388608|FontID=1|Text=DS2|Name=Designator|ReadOnlyState=1
|RECORD=41|OwnerIndex=1392|IndexInSheet=-1|OwnerPartId=-1|Location.X=77|Location.Y=162|Color=8388608|FontID=1|IsHidden=T|Text=Lumex_SML-LXFM0603SUGCTR|Name=Comment
|RECORD=44|OwnerIndex=1392
|RECORD=45|OwnerIndex=1451|IndexInSheet=-1|Description=LED, Body 1.6x0.8mm, Height 1.10mm, LXFM0603-GR|UseComponentLibrary=T|ModelName=LEDS160X80X110-2N_LXFM0603-GR|ModelType=PCBLIB|DatafileCount=1|ModelDatafileEntity0=LEDS160X80X110-2N_LXFM0603-GR|ModelDatafileKind0=PCBLib|IsCurrent=T|DatalinksLocked=T|DatabaseDatalinksLocked=T
|RECORD=46|OwnerIndex=1452
|RECORD=47|OwnerIndex=1453|DesImpCount=1|DesImp0=null
|RECORD=48|OwnerIndex=1452
|RECORD=41|OwnerIndex=1455|IndexInSheet=-1|OwnerPartId=-1|Color=8388608|FontID=1|IsHidden=T|Text=2D|Name=Available Preview Images
|RECORD=17|IndexInSheet=93|OwnerPartId=-1|Style=4|ShowNetName=F|Location.X=90|Location.Y=60|Orientation=3|Color=128|FontID=1|Text=GND
|RECORD=17|IndexInSheet=94|OwnerPartId=-1|Style=2|ShowNetName=T|Location.X=90|Location.Y=160|Orientation=1|Color=128|FontID=1|Text=VCC
|RECORD=1|LibReference=LED_Green_300mil|ComponentDescription=LED, GREEN, 574NM, 20MA, 20MCD MIN, 2.5VF MAX, 0603, 1.10MM T|PartCount=2|DisplayModeCount=1|IndexInSheet=95|OwnerPartId=-1|Location.X=150|Location.Y=130|Orientation=2|CurrentPartId=1|LibraryPath=*|SourceLibraryName=RL Research Altium Server|TargetFileName=*|AreaColor=11599871|Color=128|PartIDLocked=T|DesignItemId=LED-CMP-00021-2|AllPinCount=2
|RECORD=2|OwnerIndex=1459|OwnerPartId=1|FormalType=1|Electrical=4|PinConglomerate=35|PinLength=10|Location.X=150|Location.Y=140|Name=Cathode|Designator=K|SwapIDPart=0|PinName_PositionConglomerate=16|Name_CustomFontID=16|PinDesignator_PositionConglomerate=16|Designator_CustomFontID=16|PinPropagationDelay=0.000000E+000
|RECORD=2|OwnerIndex=1459|OwnerPartId=1|FormalType=1|Electrical=4|PinConglomerate=33|PinLength=10|Location.X=150|Location.Y=150|Name=Anode|Designator=A|SwapIDPart=0|PinName_PositionConglomerate=16|Name_CustomFontID=16|PinDesignator_PositionConglomerate=16|Designator_CustomFontID=16|PinPropagationDelay=0.000000E+000
|RECORD=6|OwnerIndex=1459|IsNotAccesible=T|IndexInSheet=2|OwnerPartId=1|LineWidth=1|Color=65280|LocationCount=6|X1=144|Y1=144|X2=141|Y2=141|X3=140|Y3=142|X4=139|Y4=139|X5=142|Y5=140|X6=141|Y6=141
|RECORD=6|OwnerIndex=1459|IsNotAccesible=T|IndexInSheet=3|OwnerPartId=1|LineWidth=1|Color=65280|LocationCount=6|X1=143|Y1=148|X2=140|Y2=145|X3=139|Y3=146|X4=138|Y4=143|X5=141|Y5=144|X6=140|Y6=145
|RECORD=3|OwnerIndex=1459|IsNotAccesible=T|IndexInSheet=4|OwnerPartId=1|Symbol=33|Location.X=150|Location.Y=140|ScaleFactor=10|Orientation=3|LineWidth=1|Color=65280
|RECORD=6|OwnerIndex=1459|IsNotAccesible=T|IndexInSheet=5|OwnerPartId=1|LineWidth=1|Color=65280|LocationCount=2|X1=153|Y1=140|X2=147|Y2=140
|RECORD=6|OwnerIndex=1459|IsNotAccesible=T|IndexInSheet=6|OwnerPartId=1|LineWidth=1|Color=65280|LocationCount=2|X1=150|Y1=150|X2=150|Y2=146
|RECORD=41|OwnerIndex=1459|IndexInSheet=7|OwnerPartId=-1|Location.X=137|Location.Y=162|Color=8388608|FontID=1|IsHidden=T|Text=Clear|Name=Lens Transparency
|RECORD=41|OwnerIndex=1459|IndexInSheet=8|OwnerPartId=-1|Location.X=137|Location.Y=162|Color=8388608|FontID=1|IsHidden=T|Text=50mcd|Name=Millicandela Rating
|RECORD=41|OwnerIndex=1459|IndexInSheet=9|OwnerPartId=-1|Location.X=137|Location.Y=162|Color=8388608|FontID=1|IsHidden=T|Name=Type
|RECORD=41|OwnerIndex=1459|IndexInSheet=10|OwnerPartId=-1|Location.X=137|Location.Y=162|Color=8388608|FontID=1|IsHidden=T|Name=Wavelength
|RECORD=41|OwnerIndex=1459|IndexInSheet=11|OwnerPartId=-1|Location.X=137|Location.Y=162|Color=8388608|FontID=1|IsHidden=T|Text=2.2V|Name=Voltage - Forward (Vf) (Typ)
|RECORD=41|OwnerIndex=1459|IndexInSheet=12|OwnerPartId=-1|Location.X=137|Location.Y=162|Color=8388608|FontID=1|IsHidden=T|Text=1.60mm L x 0.80mm W|Name=Size / Dimension
|RECORD=41|OwnerIndex=1459|IndexInSheet=13|OwnerPartId=-1|Location.X=137|Location.Y=162|Color=8388608|FontID=1|IsHidden=T|Text=85°C|Name=Max Operating Temperature
|RECORD=41|OwnerIndex=1459|IndexInSheet=14|OwnerPartId=-1|Location.X=137|Location.Y=162|Color=8388608|FontID=1|IsHidden=T|Text=-40°C|Name=Min Operating Temperature
|RECORD=41|OwnerIndex=1459|IndexInSheet=15|OwnerPartId=-1|Location.X=137|Location.Y=162|Color=8388608|FontID=1|IsHidden=T|Name=Series
|RECORD=41|OwnerIndex=1459|IndexInSheet=16|OwnerPartId=-1|Location.X=137|Location.Y=162|Color=8388608|FontID=1|IsHidden=T|Name=Character Format
|RECORD=41|OwnerIndex=1459|IndexInSheet=17|OwnerPartId=-1|Location.X=137|Location.Y=162|Color=8388608|FontID=1|IsHidden=T|Name=Number of Characters
|RECORD=41|OwnerIndex=1459|IndexInSheet=18|OwnerPartId=-1|Location.X=137|Location.Y=162|Color=8388608|FontID=1|IsHidden=T|Text=Independent|Name=Configuration
|RECORD=41|OwnerIndex=1459|IndexInSheet=19|OwnerPartId=-1|Location.X=137|Location.Y=162|Color=8388608|FontID=1|IsHidden=T|Text=838-00422-00|Name=Internal Part Number
|RECORD=41|OwnerIndex=1459|IndexInSheet=20|OwnerPartId=-1|Location.X=137|Location.Y=162|Color=8388608|FontID=1|IsHidden=T|Name=Applications
|RECORD=41|OwnerIndex=1459|IndexInSheet=21|OwnerPartId=-1|Location.X=137|Location.Y=162|Color=8388608|FontID=1|IsHidden=T|Name=Connector Type
|RECORD=41|OwnerIndex=1459|IndexInSheet=22|OwnerPartId=-1|Location.X=137|Location.Y=162|Color=8388608|FontID=1|IsHidden=T|Name=Current - DC Forward (If) (Max)
|RECORD=41|OwnerIndex=1459|IndexInSheet=23|OwnerPartId=-1|Location.X=137|Location.Y=162|Color=8388608|FontID=1|IsHidden=T|Text=120°|Name=Viewing Angle
|RECORD=41|OwnerIndex=1459|IndexInSheet=24|OwnerPartId=-1|Location.X=137|Location.Y=162|Color=8388608|FontID=1|IsHidden=T|Name=Radiant Intensity (Ie) Min @ If
|RECORD=41|OwnerIndex=1459|IndexInSheet=25|OwnerPartId=-1|Location.X=137|Location.Y=162|Color=8388608|FontID=1|IsHidden=T|Text=LED Indication - Discrete|Name=Category
|RECORD=41|OwnerIndex=1459|IndexInSheet=26|OwnerPartId=-1|Location.X=137|Location.Y=162|Color=8388608|FontID=1|IsHidden=T|Name=Display Mode
|RECORD=41|OwnerIndex=1459|IndexInSheet=27|OwnerPartId=-1|Location.X=137|Location.Y=162|Color=8388608|FontID=1|IsHidden=T|Text=Green|Name=Lens Color
|RECORD=41|OwnerIndex=1459|IndexInSheet=28|OwnerPartId=-1|Location.X=137|Location.Y=162|Color=8388608|FontID=1|IsHidden=T|Text=0603 (1608 Metric)|Name=Case/Package
|RECORD=41|OwnerIndex=1459|IndexInSheet=29|OwnerPartId=-1|Location.X=137|Location.Y=162|Color=8388608|FontID=1|IsHidden=T|Name=Voltage - Supply
|RECORD=41|OwnerIndex=1459|IndexInSheet=30|OwnerPartId=-1|Location.X=137|Location.Y=162|Color=8388608|FontID=1|IsHidden=T|Text=20mA|Name=Current - Test
|RECORD=41|OwnerIndex=1459|IndexInSheet=31|OwnerPartId=-1|Location.X=137|Location.Y=162|Color=8388608|FontID=1|IsHidden=T|Name=Data Rate
|RECORD=41|OwnerIndex=1459|IndexInSheet=32|OwnerPartId=-1|Location.X=137|Location.Y=162|Color=8388608|FontID=1|IsHidden=T|Text=574nm|Name=Wavelength - Peak
|RECORD=41|OwnerIndex=1459|IndexInSheet=33|OwnerPartId=-1|Location.X=137|Location.Y=162|Color=8388608|FontID=1|IsHidden=T|Text=1.20mm x 0.80mm|Name=Lens Size
|RECORD=41|OwnerIndex=1459|IndexInSheet=34|OwnerPartId=-1|Location.X=137|Location.Y=162|Color=8388608|FontID=1|IsHidden=T|Name=Part Status
|RECORD=41|OwnerIndex=1459|IndexInSheet=35|OwnerPartId=-1|Location.X=137|Location.Y=162|Color=8388608|FontID=1|IsHidden=T|Text=Surface Mount|Name=Mounting Type
|RECORD=41|OwnerIndex=1459|IndexInSheet=36|OwnerPartId=-1|Location.X=137|Location.Y=162|Color=8388608|FontID=1|IsHidden=T|Text=Yes|Name=RoHS
|RECORD=41|OwnerIndex=1459|IndexInSheet=37|OwnerPartId=-1|Location.X=137|Location.Y=162|Color=8388608|FontID=1|IsHidden=T|Text=Lumex Opto/Components Inc.|Name=Manufacturer
|RECORD=41|OwnerIndex=1459|IndexInSheet=38|OwnerPartId=-1|Location.X=137|Location.Y=162|Color=8388608|FontID=1|IsHidden=T|Name=Wavelength - Dominant
|RECORD=41|OwnerIndex=1459|IndexInSheet=39|OwnerPartId=-1|Location.X=137|Location.Y=162|Color=8388608|FontID=1|IsHidden=T|Name=Features
|RECORD=41|OwnerIndex=1459|IndexInSheet=40|OwnerPartId=-1|Location.X=137|Location.Y=162|Color=8388608|FontID=1|IsHidden=T|Text=1.10mm|Name=Height (Max)
|RECORD=41|OwnerIndex=1459|IndexInSheet=41|OwnerPartId=-1|Location.X=137|Location.Y=162|Color=8388608|FontID=1|IsHidden=T|Text=Digikey|Name=Supplier 1
|RECORD=41|OwnerIndex=1459|IndexInSheet=42|OwnerPartId=-1|Location.X=137|Location.Y=162|Color=8388608|FontID=1|IsHidden=T|Name=Attenuation Value
|RECORD=41|OwnerIndex=1459|IndexInSheet=43|OwnerPartId=-1|Location.X=137|Location.Y=162|Color=8388608|FontID=1|IsHidden=T|Name=Display Format
|RECORD=41|OwnerIndex=1459|IndexInSheet=44|OwnerPartId=-1|Location.X=137|Location.Y=162|Color=8388608|FontID=1|IsHidden=T|Name=Current - Supply
|RECORD=41|OwnerIndex=1459|IndexInSheet=45|OwnerPartId=-1|Location.X=137|Location.Y=162|Color=8388608|FontID=1|IsHidden=T|Text=Rectangle with Flat Top|Name=Lens Style
|RECORD=41|OwnerIndex=1459|IndexInSheet=46|OwnerPartId=-1|Location.X=137|Location.Y=162|Color=8388608|FontID=1|IsHidden=T|Name=Viewing Area
|RECORD=41|OwnerIndex=1459|IndexInSheet=47|OwnerPartId=-1|Location.X=154|Location.Y=131|Color=8388608|FontID=1|Text=Green|Name=Color
|RECORD=41|OwnerIndex=1459|IndexInSheet=48|OwnerPartId=-1|Location.X=137|Location.Y=162|Color=8388608|FontID=2|IsHidden=T|Text=https://www.digikey.com/en/products/detail/lumex-opto-components-inc/SML-LXFM0603SUGCTR/7364547?s=N4IgTCBcDaIMoFkAyBaJANAYggDANhwGY4BVAcQGEAVAJRAF0BfIA|Name=Datasheet URL
|RECORD=41|OwnerIndex=1459|IndexInSheet=49|OwnerPartId=-1|Location.X=137|Location.Y=162|Color=8388608|FontID=1|IsHidden=T|Name=Orientation
|RECORD=41|OwnerIndex=1459|IndexInSheet=50|OwnerPartId=-1|Location.X=137|Location.Y=162|Color=8388608|FontID=1|IsHidden=T|Name=Display Type
|RECORD=41|OwnerIndex=1459|IndexInSheet=51|OwnerPartId=-1|Location.X=137|Location.Y=162|Color=8388608|FontID=1|IsHidden=T|Text=67-2320-1-ND|Name=Supplier Part Number 1
|RECORD=41|OwnerIndex=1459|IndexInSheet=52|OwnerPartId=-1|Location.X=137|Location.Y=162|Color=8388608|FontID=1|IsHidden=T|Text=SML-LXFM0603SUGCTR|Name=Manufacturer Part Number
|RECORD=41|OwnerIndex=1459|IndexInSheet=53|OwnerPartId=-1|Location.X=137|Location.Y=162|Color=8388608|FontID=1|IsHidden=T|Name=Backlight
|RECORD=34|OwnerIndex=1459|IndexInSheet=-1|OwnerPartId=-1|Location.X=154|Location.Y=141|Color=8388608|FontID=1|Text=DS3|Name=Designator|ReadOnlyState=1
|RECORD=41|OwnerIndex=1459|IndexInSheet=-1|OwnerPartId=-1|Location.X=137|Location.Y=162|Color=8388608|FontID=1|IsHidden=T|Text=Lumex_SML-LXFM0603SUGCTR|Name=Comment
|RECORD=44|OwnerIndex=1459
|RECORD=45|OwnerIndex=1518|IndexInSheet=-1|Description=LED, Body 1.6x0.8mm, Height 1.10mm, LXFM0603-GR|UseComponentLibrary=T|ModelName=LEDS160X80X110-2N_LXFM0603-GR|ModelType=PCBLIB|DatafileCount=1|ModelDatafileEntity0=LEDS160X80X110-2N_LXFM0603-GR|ModelDatafileKind0=PCBLib|IsCurrent=T|DatalinksLocked=T|DatabaseDatalinksLocked=T
|RECORD=46|OwnerIndex=1519
|RECORD=47|OwnerIndex=1520|DesImpCount=1|DesImp0=null
|RECORD=48|OwnerIndex=1519
|RECORD=41|OwnerIndex=1522|IndexInSheet=-1|OwnerPartId=-1|Color=8388608|FontID=1|IsHidden=T|Text=2D|Name=Available Preview Images
|RECORD=17|IndexInSheet=96|OwnerPartId=-1|Style=2|ShowNetName=T|Location.X=150|Location.Y=160|Orientation=1|Color=128|FontID=1|Text=VCC_ANT
|RECORD=1|LibReference=1029c3af85768c4190bb7ad29bc67b5|ComponentDescription=10kO ±1% 0.063W 0402 Thick Film Chip Resistor AEC-Q200 compliant|PartCount=2|DisplayModeCount=1|IndexInSheet=97|OwnerPartId=-1|Location.X=150|Location.Y=60|Orientation=1|CurrentPartId=1|LibraryPath=*|SourceLibraryName=Altium Content Vault|TargetFileName=*|AreaColor=11599871|Color=128|PartIDLocked=T|DesignItemId=CMP-26527-000128-1|AllPinCount=2
|RECORD=2|OwnerIndex=1525|OwnerPartId=1|Electrical=4|PinConglomerate=35|PinLength=20|Location.X=150|Location.Y=80|Name=1|Designator=1|PinPropagationDelay=0.000000E+000
|RECORD=2|OwnerIndex=1525|OwnerPartId=1|Electrical=4|PinConglomerate=33|PinLength=20|Location.X=150|Location.Y=110|Name=2|Designator=2|PinPropagationDelay=0.000000E+000
|RECORD=13|OwnerIndex=1525|IsNotAccesible=T|IndexInSheet=2|OwnerPartId=1|Location.X=150|Location.Y=80|Corner.X=145|Corner.Y=83|LineWidth=1|Color=16711680
|RECORD=13|OwnerIndex=1525|IsNotAccesible=T|IndexInSheet=3|OwnerPartId=1|Location.X=145|Location.Y=83|Corner.X=155|Corner.Y=88|LineWidth=1|Color=16711680
|RECORD=13|OwnerIndex=1525|IsNotAccesible=T|IndexInSheet=4|OwnerPartId=1|Location.X=155|Location.Y=88|Corner.X=145|Corner.Y=93|LineWidth=1|Color=16711680
|RECORD=13|OwnerIndex=1525|IsNotAccesible=T|IndexInSheet=5|OwnerPartId=1|Location.X=145|Location.Y=93|Corner.X=155|Corner.Y=98|LineWidth=1|Color=16711680
|RECORD=13|OwnerIndex=1525|IsNotAccesible=T|IndexInSheet=6|OwnerPartId=1|Location.X=155|Location.Y=98|Corner.X=145|Corner.Y=103|LineWidth=1|Color=16711680
|RECORD=13|OwnerIndex=1525|IsNotAccesible=T|IndexInSheet=7|OwnerPartId=1|Location.X=145|Location.Y=103|Corner.X=155|Corner.Y=108|LineWidth=1|Color=16711680
|RECORD=13|OwnerIndex=1525|IsNotAccesible=T|IndexInSheet=8|OwnerPartId=1|Location.X=155|Location.Y=108|Corner.X=150|Corner.Y=110|LineWidth=1|Color=16711680
|RECORD=13|OwnerIndex=1525|IsNotAccesible=T|IndexInSheet=9|OwnerPartId=1|Location.X=150|Location.Y=80|Corner.X=150|Corner.Y=77|LineWidth=1|Color=16711680
|RECORD=13|OwnerIndex=1525|IsNotAccesible=T|IndexInSheet=10|OwnerPartId=1|Location.X=150|Location.Y=110|Corner.X=150|Corner.Y=113|LineWidth=1|Color=16711680
|RECORD=41|OwnerIndex=1525|IndexInSheet=11|OwnerPartId=-1|Location.X=144|Location.Y=132|Color=8388608|FontID=1|IsHidden=T|Text=0.02inch|Name=Width
|RECORD=41|OwnerIndex=1525|IndexInSheet=12|OwnerPartId=-1|Location.X=144|Location.Y=132|Color=8388608|FontID=1|IsHidden=T|Text=0402|Name=Case/Package
|RECORD=41|OwnerIndex=1525|IndexInSheet=13|OwnerPartId=-1|Location.X=144|Location.Y=132|Color=8388608|FontID=1|IsHidden=T|Text=100ppm/°C|Name=Temperature Coefficient
|RECORD=41|OwnerIndex=1525|IndexInSheet=14|OwnerPartId=-1|Location.X=144|Location.Y=132|Color=8388608|FontID=1|IsHidden=T|Text=0.5mm|Name=Depth
|RECORD=41|OwnerIndex=1525|IndexInSheet=15|OwnerPartId=-1|Location.X=144|Location.Y=132|Color=8388608|FontID=1|IsHidden=T|Text=Thick Film|Name=Resistor Type
|RECORD=41|OwnerIndex=1525|IndexInSheet=16|OwnerPartId=-1|Location.X=144|Location.Y=132|Color=8388608|FontID=1|IsHidden=T|Text=RMCF|Name=Series
|RECORD=41|OwnerIndex=1525|IndexInSheet=17|OwnerPartId=-1|Location.X=144|Location.Y=132|Color=8388608|FontID=1|IsHidden=T|Text=1mm|Name=Length
|RECORD=41|OwnerIndex=1525|IndexInSheet=18|OwnerPartId=-1|Location.X=144|Location.Y=132|Color=8388608|FontID=1|IsHidden=T|Text=62.5mW|Name=Power Rating
|RECORD=41|OwnerIndex=1525|IndexInSheet=19|OwnerPartId=-1|Location.X=144|Location.Y=132|Color=8388608|FontID=1|IsHidden=T|Text=10kR|Name=Resistance
|RECORD=41|OwnerIndex=1525|IndexInSheet=20|OwnerPartId=-1|Location.X=144|Location.Y=132|Color=8388608|FontID=1|IsHidden=T|Text=Tin|Name=Contact Plating
|RECORD=41|OwnerIndex=1525|IndexInSheet=21|OwnerPartId=-1|Location.X=144|Location.Y=132|Color=8388608|FontID=1|IsHidden=T|Text=1%|Name=Tolerance
|RECORD=41|OwnerIndex=1525|IndexInSheet=22|OwnerPartId=-1|Location.X=144|Location.Y=132|Color=8388608|FontID=1|IsHidden=T|Text=2|Name=Number of Terminations
|RECORD=41|OwnerIndex=1525|IndexInSheet=23|OwnerPartId=-1|Location.X=144|Location.Y=132|Color=8388608|FontID=1|IsHidden=T|Text=0.016inch|Name=Height
|RECORD=41|OwnerIndex=1525|IndexInSheet=24|OwnerPartId=-1|Location.X=144|Location.Y=132|Color=8388608|FontID=1|IsHidden=T|Text=Not|Name=Military Standard
|RECORD=41|OwnerIndex=1525|IndexInSheet=25|OwnerPartId=-1|Location.X=144|Location.Y=132|Color=8388608|FontID=1|IsHidden=T|Text=0402|Name=Case Code (Imperial)
|RECORD=41|OwnerIndex=1525|IndexInSheet=26|OwnerPartId=-1|Location.X=144|Location.Y=132|Color=8388608|FontID=1|IsHidden=T|Text=63mW|Name=Max Power Dissipation
|RECORD=41|OwnerIndex=1525|IndexInSheet=27|OwnerPartId=-1|Location.X=144|Location.Y=132|Color=8388608|FontID=1|IsHidden=T|Text=0402|Name=Size Code
|RECORD=41|OwnerIndex=1525|IndexInSheet=28|OwnerPartId=-1|Location.X=144|Location.Y=132|Color=8388608|FontID=1|IsHidden=T|Text=Rectangular|Name=Construction
|RECORD=41|OwnerIndex=1525|IndexInSheet=29|OwnerPartId=-1|Location.X=144|Location.Y=132|Color=8388608|FontID=1|IsHidden=T|Text=No|Name=Radiation Hardening
|RECORD=41|OwnerIndex=1525|IndexInSheet=30|OwnerPartId=-1|Location.X=144|Location.Y=132|Color=8388608|FontID=1|IsHidden=T|Text=Yes|Name=RoHS Compliant
|RECORD=41|OwnerIndex=1525|IndexInSheet=31|OwnerPartId=-1|Location.X=144|Location.Y=132|Color=8388608|FontID=1|IsHidden=T|Text=1005|Name=Case Code (Metric)
|RECORD=41|OwnerIndex=1525|IndexInSheet=32|OwnerPartId=-1|Location.X=144|Location.Y=132|Color=8388608|FontID=1|IsHidden=T|Text=Tape and Reel|Name=Packaging
|RECORD=41|OwnerIndex=1525|IndexInSheet=33|OwnerPartId=-1|Location.X=144|Location.Y=132|Color=8388608|FontID=1|IsHidden=T|Text=Lead Free|Name=Lead Free
|RECORD=41|OwnerIndex=1525|IndexInSheet=34|OwnerPartId=-1|Location.X=144|Location.Y=132|Color=8388608|FontID=1|IsHidden=T|Text=-55°C|Name=Min Operating Temperature
|RECORD=41|OwnerIndex=1525|IndexInSheet=35|OwnerPartId=-1|Location.X=144|Location.Y=132|Color=8388608|FontID=1|IsHidden=T|Text=155°C|Name=Max Operating Temperature
|RECORD=41|OwnerIndex=1525|IndexInSheet=36|OwnerPartId=-1|Location.X=144|Location.Y=132|Color=8388608|FontID=1|IsHidden=T|Text=Surface Mount|Name=Mount
|RECORD=41|OwnerIndex=1525|IndexInSheet=37|OwnerPartId=-1|Location.X=144|Location.Y=132|Color=8388608|FontID=1|IsHidden=T|Text=Automotive AEC-Q200|Name=Features
|RECORD=34|OwnerIndex=1525|IndexInSheet=-1|OwnerPartId=-1|Location.X=156|Location.Y=104|Color=8388608|FontID=1|Text=R8|Name=Designator|ReadOnlyState=1
|RECORD=41|OwnerIndex=1525|IndexInSheet=-1|OwnerPartId=1|Location.X=156|Location.Y=94|Color=8388608|FontID=1|Text=10k|Name=Comment
|RECORD=44|OwnerIndex=1525
|RECORD=45|OwnerIndex=1568|IndexInSheet=-1|UseComponentLibrary=T|ModelName=FP-RMCF0402-IPC_C|ModelType=PCBLIB|DatafileCount=1|ModelDatafileEntity0=FP-RMCF0402-IPC_C|ModelDatafileKind0=PCBLib|IsCurrent=T|DatalinksLocked=T|DatabaseDatalinksLocked=T
|RECORD=46|OwnerIndex=1569
|RECORD=48|OwnerIndex=1569
|RECORD=45|OwnerIndex=1568|IndexInSheet=-1|UseComponentLibrary=T|ModelName=FP-RMCF0402-MFG|ModelType=PCBLIB|DatafileCount=1|ModelDatafileEntity0=FP-RMCF0402-MFG|ModelDatafileKind0=PCBLib|DatalinksLocked=T|DatabaseDatalinksLocked=T
|RECORD=46|OwnerIndex=1572
|RECORD=48|OwnerIndex=1572
|RECORD=45|OwnerIndex=1568|IndexInSheet=-1|UseComponentLibrary=T|ModelName=FP-RMCF0402-IPC_A|ModelType=PCBLIB|DatafileCount=1|ModelDatafileEntity0=FP-RMCF0402-IPC_A|ModelDatafileKind0=PCBLib|DatalinksLocked=T|DatabaseDatalinksLocked=T
|RECORD=46|OwnerIndex=1575
|RECORD=48|OwnerIndex=1575
|RECORD=45|OwnerIndex=1568|IndexInSheet=-1|UseComponentLibrary=T|ModelName=FP-RMCF0402-IPC_B|ModelType=PCBLIB|DatafileCount=1|ModelDatafileEntity0=FP-RMCF0402-IPC_B|ModelDatafileKind0=PCBLib|DatalinksLocked=T|DatabaseDatalinksLocked=T
|RECORD=46|OwnerIndex=1578
|RECORD=48|OwnerIndex=1578
|RECORD=17|IndexInSheet=98|OwnerPartId=-1|Style=4|ShowNetName=F|Location.X=150|Location.Y=60|Orientation=3|Color=128|FontID=1|Text=GND
|RECORD=14|IndexInSheet=99|OwnerPartId=-1|Location.X=30|Location.Y=540|Corner.X=220|Corner.Y=630|Color=128|AreaColor=11599871
|RECORD=4|IndexInSheet=100|OwnerPartId=-1|Location.X=30|Location.Y=630|Color=8388608|FontID=15|Text=8-Position Connector
|RECORD=14|IndexInSheet=101|OwnerPartId=-1|Location.X=30|Location.Y=220|Corner.X=230|Corner.Y=510|Color=128|AreaColor=11599871
|RECORD=4|IndexInSheet=102|OwnerPartId=-1|Location.X=30|Location.Y=510|Color=8388608|FontID=15|Text=Buffer
|RECORD=14|IndexInSheet=103|OwnerPartId=-1|Location.X=30|Location.Y=30|Corner.X=230|Corner.Y=190|Color=128|AreaColor=11599871
|RECORD=4|IndexInSheet=104|OwnerPartId=-1|Location.X=30|Location.Y=190|Color=8388608|FontID=15|Text=Power Indicator LEDs
|RECORD=14|IndexInSheet=105|OwnerPartId=-1|Location.X=580|Location.Y=120|Corner.X=900|Corner.Y=690|Color=128|AreaColor=11599871
|RECORD=4|IndexInSheet=106|OwnerPartId=-1|Location.X=580|Location.Y=690|Color=8388608|FontID=15|Text=ZED-F9T GNSS Receiver
|RECORD=1|LibReference=Capacitor_300mil|ComponentDescription=CAP, CER, X5R, 1UF, 10%, 25V, 0402, 0.55MM T|PartCount=2|DisplayModeCount=1|IndexInSheet=107|OwnerPartId=-1|Location.X=600|Location.Y=660|CurrentPartId=1|LibraryPath=*|SourceLibraryName=RL Research Altium Server|TargetFileName=*|AreaColor=11599871|Color=128|PartIDLocked=T|DesignItemId=CAP-CMP-00365-3|AllPinCount=2
|RECORD=13|OwnerIndex=1590|IsNotAccesible=T|OwnerPartId=1|Location.X=590|Location.Y=648|Corner.X=610|Corner.Y=648|LineWidth=1|Color=16711680
|RECORD=6|OwnerIndex=1590|IsNotAccesible=T|IndexInSheet=1|OwnerPartId=1|LineWidth=1|Color=16711680|LocationCount=2|X1=590|Y1=642|X2=610|Y2=642
|RECORD=6|OwnerIndex=1590|IsNotAccesible=T|IndexInSheet=2|OwnerPartId=1|LineWidth=1|Color=16711680|LocationCount=2|X1=600|Y1=640|X2=600|Y2=642
|RECORD=6|OwnerIndex=1590|IsNotAccesible=T|IndexInSheet=3|OwnerPartId=1|LineWidth=1|Color=16711680|LocationCount=2|X1=600|Y1=650|X2=600|Y2=648
|RECORD=2|OwnerIndex=1590|OwnerPartId=1|FormalType=1|Electrical=4|PinConglomerate=33|PinLength=10|Location.X=600|Location.Y=650|Name=1|Designator=1|SwapIDPart=0|PinName_PositionConglomerate=16|Name_CustomFontID=16|PinDesignator_PositionConglomerate=16|Designator_CustomFontID=16|PinPropagationDelay=0.000000E+000
|RECORD=2|OwnerIndex=1590|OwnerPartId=1|FormalType=1|Electrical=4|PinConglomerate=35|PinLength=10|Location.X=600|Location.Y=640|Name=2|Designator=2|SwapIDPart=0|PinName_PositionConglomerate=16|Name_CustomFontID=16|PinDesignator_PositionConglomerate=16|Designator_CustomFontID=16|PinPropagationDelay=0.000000E+000
|RECORD=41|OwnerIndex=1590|IndexInSheet=6|OwnerPartId=-1|Location.X=589|Location.Y=675|Color=8388608|FontID=2|IsHidden=T|Text=https://www.digikey.com/en/products/detail/murata-electronics/GRM155R61E105KA12D/4905139?s=N4IgTCBcDaIOICUCyBGArGhA2FBRFADGgNICCKYAIiALoC%2BQA|Name=Datasheet URL
|RECORD=41|OwnerIndex=1590|IndexInSheet=7|OwnerPartId=-1|Location.X=589|Location.Y=675|Color=8388608|FontID=1|IsHidden=T|Text=Yes|Name=RoHS
|RECORD=41|OwnerIndex=1590|IndexInSheet=8|OwnerPartId=-1|Location.X=589|Location.Y=675|Color=8388608|FontID=1|IsHidden=T|Text=Surface Mount, MLCC|Name=Mounting Type
|RECORD=41|OwnerIndex=1590|IndexInSheet=9|OwnerPartId=-1|Location.X=589|Location.Y=675|Color=8388608|FontID=1|IsHidden=T|Name=Voltage - Rated
|RECORD=41|OwnerIndex=1590|IndexInSheet=10|OwnerPartId=-1|Location.X=589|Location.Y=675|Color=8388608|FontID=1|IsHidden=T|Text=85°C|Name=Max Operating Temperature
|RECORD=41|OwnerIndex=1590|IndexInSheet=11|OwnerPartId=-1|Location.X=589|Location.Y=675|Color=8388608|FontID=1|IsHidden=T|Text=Ceramic Capacitors|Name=Category
|RECORD=41|OwnerIndex=1590|IndexInSheet=12|OwnerPartId=-1|Location.X=589|Location.Y=675|Color=8388608|FontID=1|IsHidden=T|Text=0.022" (0.55mm)|Name=Height
|RECORD=41|OwnerIndex=1590|IndexInSheet=13|OwnerPartId=-1|Location.X=589|Location.Y=675|Color=8388608|FontID=1|IsHidden=T|Name=Ratings
|RECORD=41|OwnerIndex=1590|IndexInSheet=14|OwnerPartId=-1|Location.X=589|Location.Y=675|Color=8388608|FontID=1|IsHidden=T|Name=Lead Spacing
|RECORD=41|OwnerIndex=1590|IndexInSheet=15|OwnerPartId=-1|Location.X=611|Location.Y=641|Color=8388608|FontID=1|Name=Part Status
|RECORD=41|OwnerIndex=1590|IndexInSheet=16|OwnerPartId=-1|Location.X=589|Location.Y=675|Color=8388608|FontID=1|IsHidden=T|Text=Digikey|Name=Supplier 1
|RECORD=41|OwnerIndex=1590|IndexInSheet=17|OwnerPartId=-1|Location.X=589|Location.Y=675|Color=8388608|FontID=1|IsHidden=T|Name=Lead Style
|RECORD=41|OwnerIndex=1590|IndexInSheet=18|OwnerPartId=-1|Location.X=589|Location.Y=675|Color=8388608|FontID=1|IsHidden=T|Text=GRM155R61E105KA12D|Name=Manufacturer Part Number
|RECORD=41|OwnerIndex=1590|IndexInSheet=19|OwnerPartId=-1|Location.X=589|Location.Y=675|Color=8388608|FontID=1|IsHidden=T|Name=Features
|RECORD=41|OwnerIndex=1590|IndexInSheet=20|OwnerPartId=-1|Location.X=611|Location.Y=631|Color=8388608|FontID=1|Text=±10%|Name=Tolerance
|RECORD=41|OwnerIndex=1590|IndexInSheet=21|OwnerPartId=-1|Location.X=611|Location.Y=621|Color=8388608|FontID=1|Text=25V|Name=Voltage Rating
|RECORD=41|OwnerIndex=1590|IndexInSheet=22|OwnerPartId=-1|Location.X=589|Location.Y=695|Color=8388608|FontID=1|IsHidden=T|Text=X5R|Name=Temperature Coefficient
|RECORD=41|OwnerIndex=1590|IndexInSheet=23|OwnerPartId=-1|Location.X=589|Location.Y=695|Color=8388608|FontID=1|IsHidden=T|Name=Voltage Rating - AC
|RECORD=41|OwnerIndex=1590|IndexInSheet=24|OwnerPartId=-1|Location.X=589|Location.Y=695|Color=8388608|FontID=1|IsHidden=T|Text=-55°C|Name=Min Operating Temperature
|RECORD=41|OwnerIndex=1590|IndexInSheet=25|OwnerPartId=-1|Location.X=589|Location.Y=695|Color=8388608|FontID=1|IsHidden=T|Name=Type
|RECORD=41|OwnerIndex=1590|IndexInSheet=26|OwnerPartId=-1|Location.X=589|Location.Y=695|Color=8388608|FontID=1|IsHidden=T|Text=0402 (1005 Metric)|Name=Case/Package
|RECORD=41|OwnerIndex=1590|IndexInSheet=27|OwnerPartId=-1|Location.X=589|Location.Y=695|Color=8388608|FontID=1|IsHidden=T|Text=Non-polar|Name=Polarization
|RECORD=41|OwnerIndex=1590|IndexInSheet=28|OwnerPartId=-1|Location.X=589|Location.Y=695|Color=8388608|FontID=1|IsHidden=T|Text=Murata|Name=Manufacturer
|RECORD=41|OwnerIndex=1590|IndexInSheet=29|OwnerPartId=-1|Location.X=589|Location.Y=695|Color=8388608|FontID=1|IsHidden=T|Text=0.039" L x 0.020" W (1.00mm x 0.50mm)|Name=Size / Dimension
|RECORD=41|OwnerIndex=1590|IndexInSheet=30|OwnerPartId=-1|Location.X=589|Location.Y=695|Color=8388608|FontID=1|IsHidden=T|Name=Impedance
|RECORD=41|OwnerIndex=1590|IndexInSheet=31|OwnerPartId=-1|Location.X=589|Location.Y=695|Color=8388608|FontID=1|IsHidden=T|Text=825-00099-00|Name=Internal Part Number
|RECORD=41|OwnerIndex=1590|IndexInSheet=32|OwnerPartId=-1|Location.X=589|Location.Y=695|Color=8388608|FontID=1|IsHidden=T|Text=Ceramic|Name=Composition
|RECORD=41|OwnerIndex=1590|IndexInSheet=33|OwnerPartId=-1|Location.X=589|Location.Y=695|Color=8388608|FontID=1|IsHidden=T|Name=Thickness (Max)
|RECORD=41|OwnerIndex=1590|IndexInSheet=34|OwnerPartId=-1|Location.X=589|Location.Y=695|Color=8388608|FontID=1|IsHidden=T|Text=490-10017-1-ND|Name=Supplier Part Number 1
|RECORD=41|OwnerIndex=1590|IndexInSheet=35|OwnerPartId=-1|Location.X=589|Location.Y=695|Color=8388608|FontID=1|IsHidden=T|Name=ESR (Equivalent Series Resistance)
|RECORD=41|OwnerIndex=1590|IndexInSheet=36|OwnerPartId=-1|Location.X=589|Location.Y=695|Color=8388608|FontID=1|IsHidden=T|Text=GRM155R61E|Name=Series
|RECORD=41|OwnerIndex=1590|IndexInSheet=37|OwnerPartId=-1|Location.X=589|Location.Y=695|Color=8388608|FontID=1|IsHidden=T|Name=Failure Rate
|RECORD=41|OwnerIndex=1590|IndexInSheet=38|OwnerPartId=-1|Location.X=589|Location.Y=695|Color=8388608|FontID=1|IsHidden=T|Text=General Purpose|Name=Applications
|RECORD=41|OwnerIndex=1590|IndexInSheet=39|OwnerPartId=-1|Location.X=611|Location.Y=611|Color=8388608|FontID=1|Text=1µF|Name=Capacitance
|RECORD=41|OwnerIndex=1590|IndexInSheet=40|OwnerPartId=-1|Location.X=589|Location.Y=705|Color=8388608|FontID=1|IsHidden=T|Name=Voltage Rating - DC
|RECORD=41|OwnerIndex=1590|IndexInSheet=41|OwnerPartId=-1|Location.X=589|Location.Y=705|Color=8388608|FontID=1|IsHidden=T|Name=Dielectric Material
|RECORD=34|OwnerIndex=1590|IndexInSheet=-1|OwnerPartId=-1|Location.X=611|Location.Y=641|Color=8388608|FontID=1|Text=C1|Name=Designator|ReadOnlyState=1
|RECORD=41|OwnerIndex=1590|IndexInSheet=-1|OwnerPartId=-1|Location.X=595|Location.Y=645|Color=8388608|FontID=1|IsHidden=T|Text=Murata_GRM155R61E105KA12D|Name=Comment
|RECORD=44|OwnerIndex=1590
|RECORD=45|OwnerIndex=1637|IndexInSheet=-1|Description=Chip Capacitor, Body 1.0x0.5mm, Hieght 0.55mm|UseComponentLibrary=T|ModelName=CAPC1005X055N|ModelType=PCBLIB|DatafileCount=1|ModelDatafileEntity0=CAPC1005X055N|ModelDatafileKind0=PCBLib|IsCurrent=T|DatalinksLocked=T|DatabaseDatalinksLocked=T
|RECORD=46|OwnerIndex=1638
|RECORD=48|OwnerIndex=1638
|RECORD=41|OwnerIndex=1640|IndexInSheet=-1|OwnerPartId=-1|Color=8388608|FontID=1|IsHidden=T|Text=2D|Name=Available Preview Images
|RECORD=17|IndexInSheet=108|OwnerPartId=-1|Style=4|ShowNetName=F|Location.X=600|Location.Y=630|Orientation=3|Color=128|FontID=1|Text=GND
|RECORD=1|LibReference=Capacitor_300mil|ComponentDescription=CAP, CER, X5R, 1UF, 10%, 25V, 0402, 0.55MM T|PartCount=2|DisplayModeCount=1|IndexInSheet=109|OwnerPartId=-1|Location.X=650|Location.Y=570|CurrentPartId=1|LibraryPath=*|SourceLibraryName=RL Research Altium Server|TargetFileName=*|AreaColor=11599871|Color=128|PartIDLocked=T|DesignItemId=CAP-CMP-00365-3|AllPinCount=2
|RECORD=13|OwnerIndex=1643|IsNotAccesible=T|OwnerPartId=1|Location.X=640|Location.Y=558|Corner.X=660|Corner.Y=558|LineWidth=1|Color=16711680
|RECORD=6|OwnerIndex=1643|IsNotAccesible=T|IndexInSheet=1|OwnerPartId=1|LineWidth=1|Color=16711680|LocationCount=2|X1=640|Y1=552|X2=660|Y2=552
|RECORD=6|OwnerIndex=1643|IsNotAccesible=T|IndexInSheet=2|OwnerPartId=1|LineWidth=1|Color=16711680|LocationCount=2|X1=650|Y1=550|X2=650|Y2=552
|RECORD=6|OwnerIndex=1643|IsNotAccesible=T|IndexInSheet=3|OwnerPartId=1|LineWidth=1|Color=16711680|LocationCount=2|X1=650|Y1=560|X2=650|Y2=558
|RECORD=2|OwnerIndex=1643|OwnerPartId=1|FormalType=1|Electrical=4|PinConglomerate=33|PinLength=10|Location.X=650|Location.Y=560|Name=1|Designator=1|SwapIDPart=0|PinName_PositionConglomerate=16|Name_CustomFontID=16|PinDesignator_PositionConglomerate=16|Designator_CustomFontID=16|PinPropagationDelay=0.000000E+000
|RECORD=2|OwnerIndex=1643|OwnerPartId=1|FormalType=1|Electrical=4|PinConglomerate=35|PinLength=10|Location.X=650|Location.Y=550|Name=2|Designator=2|SwapIDPart=0|PinName_PositionConglomerate=16|Name_CustomFontID=16|PinDesignator_PositionConglomerate=16|Designator_CustomFontID=16|PinPropagationDelay=0.000000E+000
|RECORD=41|OwnerIndex=1643|IndexInSheet=6|OwnerPartId=-1|Location.X=639|Location.Y=585|Color=8388608|FontID=2|IsHidden=T|Text=https://www.digikey.com/en/products/detail/murata-electronics/GRM155R61E105KA12D/4905139?s=N4IgTCBcDaIOICUCyBGArGhA2FBRFADGgNICCKYAIiALoC%2BQA|Name=Datasheet URL
|RECORD=41|OwnerIndex=1643|IndexInSheet=7|OwnerPartId=-1|Location.X=639|Location.Y=585|Color=8388608|FontID=1|IsHidden=T|Text=Yes|Name=RoHS
|RECORD=41|OwnerIndex=1643|IndexInSheet=8|OwnerPartId=-1|Location.X=639|Location.Y=585|Color=8388608|FontID=1|IsHidden=T|Text=Surface Mount, MLCC|Name=Mounting Type
|RECORD=41|OwnerIndex=1643|IndexInSheet=9|OwnerPartId=-1|Location.X=639|Location.Y=585|Color=8388608|FontID=1|IsHidden=T|Name=Voltage - Rated
|RECORD=41|OwnerIndex=1643|IndexInSheet=10|OwnerPartId=-1|Location.X=639|Location.Y=585|Color=8388608|FontID=1|IsHidden=T|Text=85°C|Name=Max Operating Temperature
|RECORD=41|OwnerIndex=1643|IndexInSheet=11|OwnerPartId=-1|Location.X=639|Location.Y=585|Color=8388608|FontID=1|IsHidden=T|Text=Ceramic Capacitors|Name=Category
|RECORD=41|OwnerIndex=1643|IndexInSheet=12|OwnerPartId=-1|Location.X=639|Location.Y=585|Color=8388608|FontID=1|IsHidden=T|Text=0.022" (0.55mm)|Name=Height
|RECORD=41|OwnerIndex=1643|IndexInSheet=13|OwnerPartId=-1|Location.X=639|Location.Y=585|Color=8388608|FontID=1|IsHidden=T|Name=Ratings
|RECORD=41|OwnerIndex=1643|IndexInSheet=14|OwnerPartId=-1|Location.X=639|Location.Y=585|Color=8388608|FontID=1|IsHidden=T|Name=Lead Spacing
|RECORD=41|OwnerIndex=1643|IndexInSheet=15|OwnerPartId=-1|Location.X=661|Location.Y=551|Color=8388608|FontID=1|Name=Part Status
|RECORD=41|OwnerIndex=1643|IndexInSheet=16|OwnerPartId=-1|Location.X=639|Location.Y=585|Color=8388608|FontID=1|IsHidden=T|Text=Digikey|Name=Supplier 1
|RECORD=41|OwnerIndex=1643|IndexInSheet=17|OwnerPartId=-1|Location.X=639|Location.Y=585|Color=8388608|FontID=1|IsHidden=T|Name=Lead Style
|RECORD=41|OwnerIndex=1643|IndexInSheet=18|OwnerPartId=-1|Location.X=639|Location.Y=585|Color=8388608|FontID=1|IsHidden=T|Text=GRM155R61E105KA12D|Name=Manufacturer Part Number
|RECORD=41|OwnerIndex=1643|IndexInSheet=19|OwnerPartId=-1|Location.X=639|Location.Y=585|Color=8388608|FontID=1|IsHidden=T|Name=Features
|RECORD=41|OwnerIndex=1643|IndexInSheet=20|OwnerPartId=-1|Location.X=661|Location.Y=541|Color=8388608|FontID=1|Text=±10%|Name=Tolerance
|RECORD=41|OwnerIndex=1643|IndexInSheet=21|OwnerPartId=-1|Location.X=661|Location.Y=531|Color=8388608|FontID=1|Text=25V|Name=Voltage Rating
|RECORD=41|OwnerIndex=1643|IndexInSheet=22|OwnerPartId=-1|Location.X=639|Location.Y=605|Color=8388608|FontID=1|IsHidden=T|Text=X5R|Name=Temperature Coefficient
|RECORD=41|OwnerIndex=1643|IndexInSheet=23|OwnerPartId=-1|Location.X=639|Location.Y=605|Color=8388608|FontID=1|IsHidden=T|Name=Voltage Rating - AC
|RECORD=41|OwnerIndex=1643|IndexInSheet=24|OwnerPartId=-1|Location.X=639|Location.Y=605|Color=8388608|FontID=1|IsHidden=T|Text=-55°C|Name=Min Operating Temperature
|RECORD=41|OwnerIndex=1643|IndexInSheet=25|OwnerPartId=-1|Location.X=639|Location.Y=605|Color=8388608|FontID=1|IsHidden=T|Name=Type
|RECORD=41|OwnerIndex=1643|IndexInSheet=26|OwnerPartId=-1|Location.X=639|Location.Y=605|Color=8388608|FontID=1|IsHidden=T|Text=0402 (1005 Metric)|Name=Case/Package
|RECORD=41|OwnerIndex=1643|IndexInSheet=27|OwnerPartId=-1|Location.X=639|Location.Y=605|Color=8388608|FontID=1|IsHidden=T|Text=Non-polar|Name=Polarization
|RECORD=41|OwnerIndex=1643|IndexInSheet=28|OwnerPartId=-1|Location.X=639|Location.Y=605|Color=8388608|FontID=1|IsHidden=T|Text=Murata|Name=Manufacturer
|RECORD=41|OwnerIndex=1643|IndexInSheet=29|OwnerPartId=-1|Location.X=639|Location.Y=605|Color=8388608|FontID=1|IsHidden=T|Text=0.039" L x 0.020" W (1.00mm x 0.50mm)|Name=Size / Dimension
|RECORD=41|OwnerIndex=1643|IndexInSheet=30|OwnerPartId=-1|Location.X=639|Location.Y=605|Color=8388608|FontID=1|IsHidden=T|Name=Impedance
|RECORD=41|OwnerIndex=1643|IndexInSheet=31|OwnerPartId=-1|Location.X=639|Location.Y=605|Color=8388608|FontID=1|IsHidden=T|Text=825-00099-00|Name=Internal Part Number
|RECORD=41|OwnerIndex=1643|IndexInSheet=32|OwnerPartId=-1|Location.X=639|Location.Y=605|Color=8388608|FontID=1|IsHidden=T|Text=Ceramic|Name=Composition
|RECORD=41|OwnerIndex=1643|IndexInSheet=33|OwnerPartId=-1|Location.X=639|Location.Y=605|Color=8388608|FontID=1|IsHidden=T|Name=Thickness (Max)
|RECORD=41|OwnerIndex=1643|IndexInSheet=34|OwnerPartId=-1|Location.X=639|Location.Y=605|Color=8388608|FontID=1|IsHidden=T|Text=490-10017-1-ND|Name=Supplier Part Number 1
|RECORD=41|OwnerIndex=1643|IndexInSheet=35|OwnerPartId=-1|Location.X=639|Location.Y=605|Color=8388608|FontID=1|IsHidden=T|Name=ESR (Equivalent Series Resistance)
|RECORD=41|OwnerIndex=1643|IndexInSheet=36|OwnerPartId=-1|Location.X=639|Location.Y=605|Color=8388608|FontID=1|IsHidden=T|Text=GRM155R61E|Name=Series
|RECORD=41|OwnerIndex=1643|IndexInSheet=37|OwnerPartId=-1|Location.X=639|Location.Y=605|Color=8388608|FontID=1|IsHidden=T|Name=Failure Rate
|RECORD=41|OwnerIndex=1643|IndexInSheet=38|OwnerPartId=-1|Location.X=639|Location.Y=605|Color=8388608|FontID=1|IsHidden=T|Text=General Purpose|Name=Applications
|RECORD=41|OwnerIndex=1643|IndexInSheet=39|OwnerPartId=-1|Location.X=661|Location.Y=521|Color=8388608|FontID=1|Text=1µF|Name=Capacitance
|RECORD=41|OwnerIndex=1643|IndexInSheet=40|OwnerPartId=-1|Location.X=639|Location.Y=615|Color=8388608|FontID=1|IsHidden=T|Name=Voltage Rating - DC
|RECORD=41|OwnerIndex=1643|IndexInSheet=41|OwnerPartId=-1|Location.X=639|Location.Y=615|Color=8388608|FontID=1|IsHidden=T|Name=Dielectric Material
|RECORD=34|OwnerIndex=1643|IndexInSheet=-1|OwnerPartId=-1|Location.X=661|Location.Y=551|Color=8388608|FontID=1|Text=C4|Name=Designator|ReadOnlyState=1
|RECORD=41|OwnerIndex=1643|IndexInSheet=-1|OwnerPartId=-1|Location.X=645|Location.Y=555|Color=8388608|FontID=1|IsHidden=T|Text=Murata_GRM155R61E105KA12D|Name=Comment
|RECORD=44|OwnerIndex=1643
|RECORD=45|OwnerIndex=1690|IndexInSheet=-1|Description=Chip Capacitor, Body 1.0x0.5mm, Hieght 0.55mm|UseComponentLibrary=T|ModelName=CAPC1005X055N|ModelType=PCBLIB|DatafileCount=1|ModelDatafileEntity0=CAPC1005X055N|ModelDatafileKind0=PCBLib|IsCurrent=T|DatalinksLocked=T|DatabaseDatalinksLocked=T
|RECORD=46|OwnerIndex=1691
|RECORD=48|OwnerIndex=1691
|RECORD=41|OwnerIndex=1693|IndexInSheet=-1|OwnerPartId=-1|Color=8388608|FontID=1|IsHidden=T|Text=2D|Name=Available Preview Images
|RECORD=17|IndexInSheet=110|OwnerPartId=-1|Style=4|ShowNetName=F|Location.X=650|Location.Y=540|Orientation=3|Color=128|FontID=1|Text=GND
|RECORD=28|IndexInSheet=111|OwnerPartId=-1|Location.X=510|Location.Y=30|Corner.X=570|Corner.Y=50|AreaColor=16777215|FontID=1|IsSolid=T|Alignment=1|WordWrap=T|ClipToRect=T|Text=RESET_N has internal pull-up|TextMargin_Frac=5
|RECORD=25|IndexInSheet=112|OwnerPartId=-1|Location.X=260|Location.Y=160|Color=128|FontID=1|Text=RXD_IN
|RECORD=25|IndexInSheet=113|OwnerPartId=-1|Location.X=420|Location.Y=160|Justification=2|Color=128|FontID=1|Text=RXD
|RECORD=25|IndexInSheet=114|OwnerPartId=-1|Location.X=260|Location.Y=100|Color=128|FontID=1|Text=TXD
|RECORD=25|IndexInSheet=115|OwnerPartId=-1|Location.X=420|Location.Y=100|Justification=2|Color=128|FontID=1|Text=TXD_OUT
|RECORD=14|IndexInSheet=116|OwnerPartId=-1|Location.X=240|Location.Y=30|Corner.X=440|Corner.Y=190|Color=128|AreaColor=11599871
|RECORD=4|IndexInSheet=117|OwnerPartId=-1|Location.X=240|Location.Y=190|Color=8388608|FontID=15|Text=Buffer Bypass Resistors
|RECORD=1|LibReference=1029c3af85768c4190bb7ad29bc67b5|ComponentDescription=10kO ±1% 0.063W 0402 Thick Film Chip Resistor AEC-Q200 compliant|PartCount=2|DisplayModeCount=1|IndexInSheet=118|OwnerPartId=-1|Location.X=370|Location.Y=160|Orientation=2|CurrentPartId=1|LibraryPath=*|SourceLibraryName=Altium Content Vault|TargetFileName=*|AreaColor=11599871|Color=128|PartIDLocked=T|DesignItemId=CMP-26527-000128-1|AllPinCount=2
|RECORD=2|OwnerIndex=1703|OwnerPartId=1|Electrical=4|PinConglomerate=32|PinLength=20|Location.X=350|Location.Y=160|Name=1|Designator=1|PinPropagationDelay=0.000000E+000
|RECORD=2|OwnerIndex=1703|OwnerPartId=1|Electrical=4|PinConglomerate=34|PinLength=20|Location.X=320|Location.Y=160|Name=2|Designator=2|PinPropagationDelay=0.000000E+000
|RECORD=13|OwnerIndex=1703|IsNotAccesible=T|IndexInSheet=2|OwnerPartId=1|Location.X=350|Location.Y=160|Corner.X=347|Corner.Y=155|LineWidth=1|Color=16711680
|RECORD=13|OwnerIndex=1703|IsNotAccesible=T|IndexInSheet=3|OwnerPartId=1|Location.X=347|Location.Y=155|Corner.X=342|Corner.Y=165|LineWidth=1|Color=16711680
|RECORD=13|OwnerIndex=1703|IsNotAccesible=T|IndexInSheet=4|OwnerPartId=1|Location.X=342|Location.Y=165|Corner.X=337|Corner.Y=155|LineWidth=1|Color=16711680
|RECORD=13|OwnerIndex=1703|IsNotAccesible=T|IndexInSheet=5|OwnerPartId=1|Location.X=337|Location.Y=155|Corner.X=332|Corner.Y=165|LineWidth=1|Color=16711680
|RECORD=13|OwnerIndex=1703|IsNotAccesible=T|IndexInSheet=6|OwnerPartId=1|Location.X=332|Location.Y=165|Corner.X=327|Corner.Y=155|LineWidth=1|Color=16711680
|RECORD=13|OwnerIndex=1703|IsNotAccesible=T|IndexInSheet=7|OwnerPartId=1|Location.X=327|Location.Y=155|Corner.X=322|Corner.Y=165|LineWidth=1|Color=16711680
|RECORD=13|OwnerIndex=1703|IsNotAccesible=T|IndexInSheet=8|OwnerPartId=1|Location.X=322|Location.Y=165|Corner.X=320|Corner.Y=160|LineWidth=1|Color=16711680
|RECORD=13|OwnerIndex=1703|IsNotAccesible=T|IndexInSheet=9|OwnerPartId=1|Location.X=350|Location.Y=160|Corner.X=353|Corner.Y=160|LineWidth=1|Color=16711680
|RECORD=13|OwnerIndex=1703|IsNotAccesible=T|IndexInSheet=10|OwnerPartId=1|Location.X=320|Location.Y=160|Corner.X=317|Corner.Y=160|LineWidth=1|Color=16711680
|RECORD=41|OwnerIndex=1703|IndexInSheet=11|OwnerPartId=-1|Location.X=298|Location.Y=166|Color=8388608|FontID=1|IsHidden=T|Text=0.02inch|Name=Width
|RECORD=41|OwnerIndex=1703|IndexInSheet=12|OwnerPartId=-1|Location.X=298|Location.Y=166|Color=8388608|FontID=1|IsHidden=T|Text=0402|Name=Case/Package
|RECORD=41|OwnerIndex=1703|IndexInSheet=13|OwnerPartId=-1|Location.X=298|Location.Y=166|Color=8388608|FontID=1|IsHidden=T|Text=100ppm/°C|Name=Temperature Coefficient
|RECORD=41|OwnerIndex=1703|IndexInSheet=14|OwnerPartId=-1|Location.X=298|Location.Y=166|Color=8388608|FontID=1|IsHidden=T|Text=0.5mm|Name=Depth
|RECORD=41|OwnerIndex=1703|IndexInSheet=15|OwnerPartId=-1|Location.X=298|Location.Y=166|Color=8388608|FontID=1|IsHidden=T|Text=Thick Film|Name=Resistor Type
|RECORD=41|OwnerIndex=1703|IndexInSheet=16|OwnerPartId=-1|Location.X=298|Location.Y=166|Color=8388608|FontID=1|IsHidden=T|Text=RMCF|Name=Series
|RECORD=41|OwnerIndex=1703|IndexInSheet=17|OwnerPartId=-1|Location.X=298|Location.Y=166|Color=8388608|FontID=1|IsHidden=T|Text=1mm|Name=Length
|RECORD=41|OwnerIndex=1703|IndexInSheet=18|OwnerPartId=-1|Location.X=298|Location.Y=166|Color=8388608|FontID=1|IsHidden=T|Text=62.5mW|Name=Power Rating
|RECORD=41|OwnerIndex=1703|IndexInSheet=19|OwnerPartId=-1|Location.X=298|Location.Y=166|Color=8388608|FontID=1|IsHidden=T|Text=10kR|Name=Resistance
|RECORD=41|OwnerIndex=1703|IndexInSheet=20|OwnerPartId=-1|Location.X=298|Location.Y=166|Color=8388608|FontID=1|IsHidden=T|Text=Tin|Name=Contact Plating
|RECORD=41|OwnerIndex=1703|IndexInSheet=21|OwnerPartId=-1|Location.X=298|Location.Y=166|Color=8388608|FontID=1|IsHidden=T|Text=1%|Name=Tolerance
|RECORD=41|OwnerIndex=1703|IndexInSheet=22|OwnerPartId=-1|Location.X=298|Location.Y=166|Color=8388608|FontID=1|IsHidden=T|Text=2|Name=Number of Terminations
|RECORD=41|OwnerIndex=1703|IndexInSheet=23|OwnerPartId=-1|Location.X=298|Location.Y=166|Color=8388608|FontID=1|IsHidden=T|Text=0.016inch|Name=Height
|RECORD=41|OwnerIndex=1703|IndexInSheet=24|OwnerPartId=-1|Location.X=298|Location.Y=166|Color=8388608|FontID=1|IsHidden=T|Text=Not|Name=Military Standard
|RECORD=41|OwnerIndex=1703|IndexInSheet=25|OwnerPartId=-1|Location.X=298|Location.Y=166|Color=8388608|FontID=1|IsHidden=T|Text=0402|Name=Case Code (Imperial)
|RECORD=41|OwnerIndex=1703|IndexInSheet=26|OwnerPartId=-1|Location.X=298|Location.Y=166|Color=8388608|FontID=1|IsHidden=T|Text=63mW|Name=Max Power Dissipation
|RECORD=41|OwnerIndex=1703|IndexInSheet=27|OwnerPartId=-1|Location.X=298|Location.Y=166|Color=8388608|FontID=1|IsHidden=T|Text=0402|Name=Size Code
|RECORD=41|OwnerIndex=1703|IndexInSheet=28|OwnerPartId=-1|Location.X=298|Location.Y=166|Color=8388608|FontID=1|IsHidden=T|Text=Rectangular|Name=Construction
|RECORD=41|OwnerIndex=1703|IndexInSheet=29|OwnerPartId=-1|Location.X=298|Location.Y=166|Color=8388608|FontID=1|IsHidden=T|Text=No|Name=Radiation Hardening
|RECORD=41|OwnerIndex=1703|IndexInSheet=30|OwnerPartId=-1|Location.X=298|Location.Y=166|Color=8388608|FontID=1|IsHidden=T|Text=Yes|Name=RoHS Compliant
|RECORD=41|OwnerIndex=1703|IndexInSheet=31|OwnerPartId=-1|Location.X=298|Location.Y=166|Color=8388608|FontID=1|IsHidden=T|Text=1005|Name=Case Code (Metric)
|RECORD=41|OwnerIndex=1703|IndexInSheet=32|OwnerPartId=-1|Location.X=298|Location.Y=166|Color=8388608|FontID=1|IsHidden=T|Text=Tape and Reel|Name=Packaging
|RECORD=41|OwnerIndex=1703|IndexInSheet=33|OwnerPartId=-1|Location.X=298|Location.Y=166|Color=8388608|FontID=1|IsHidden=T|Text=Lead Free|Name=Lead Free
|RECORD=41|OwnerIndex=1703|IndexInSheet=34|OwnerPartId=-1|Location.X=298|Location.Y=166|Color=8388608|FontID=1|IsHidden=T|Text=-55°C|Name=Min Operating Temperature
|RECORD=41|OwnerIndex=1703|IndexInSheet=35|OwnerPartId=-1|Location.X=298|Location.Y=166|Color=8388608|FontID=1|IsHidden=T|Text=155°C|Name=Max Operating Temperature
|RECORD=41|OwnerIndex=1703|IndexInSheet=36|OwnerPartId=-1|Location.X=298|Location.Y=166|Color=8388608|FontID=1|IsHidden=T|Text=Surface Mount|Name=Mount
|RECORD=41|OwnerIndex=1703|IndexInSheet=37|OwnerPartId=-1|Location.X=298|Location.Y=166|Color=8388608|FontID=1|IsHidden=T|Text=Automotive AEC-Q200|Name=Features
|RECORD=34|OwnerIndex=1703|IndexInSheet=-1|OwnerPartId=-1|Location.X=316|Location.Y=166|Color=8388608|FontID=1|Text=R5|Name=Designator|ReadOnlyState=1
|RECORD=41|OwnerIndex=1703|IndexInSheet=-1|OwnerPartId=1|Location.X=316|Location.Y=144|Color=8388608|FontID=1|Text=10k|Name=Comment
|RECORD=44|OwnerIndex=1703
|RECORD=45|OwnerIndex=1746|IndexInSheet=-1|UseComponentLibrary=T|ModelName=FP-RMCF0402-IPC_C|ModelType=PCBLIB|DatafileCount=1|ModelDatafileEntity0=FP-RMCF0402-IPC_C|ModelDatafileKind0=PCBLib|IsCurrent=T|DatalinksLocked=T|DatabaseDatalinksLocked=T
|RECORD=46|OwnerIndex=1747
|RECORD=48|OwnerIndex=1747
|RECORD=45|OwnerIndex=1746|IndexInSheet=-1|UseComponentLibrary=T|ModelName=FP-RMCF0402-MFG|ModelType=PCBLIB|DatafileCount=1|ModelDatafileEntity0=FP-RMCF0402-MFG|ModelDatafileKind0=PCBLib|DatalinksLocked=T|DatabaseDatalinksLocked=T
|RECORD=46|OwnerIndex=1750
|RECORD=48|OwnerIndex=1750
|RECORD=45|OwnerIndex=1746|IndexInSheet=-1|UseComponentLibrary=T|ModelName=FP-RMCF0402-IPC_A|ModelType=PCBLIB|DatafileCount=1|ModelDatafileEntity0=FP-RMCF0402-IPC_A|ModelDatafileKind0=PCBLib|DatalinksLocked=T|DatabaseDatalinksLocked=T
|RECORD=46|OwnerIndex=1753
|RECORD=48|OwnerIndex=1753
|RECORD=45|OwnerIndex=1746|IndexInSheet=-1|UseComponentLibrary=T|ModelName=FP-RMCF0402-IPC_B|ModelType=PCBLIB|DatafileCount=1|ModelDatafileEntity0=FP-RMCF0402-IPC_B|ModelDatafileKind0=PCBLib|DatalinksLocked=T|DatabaseDatalinksLocked=T
|RECORD=46|OwnerIndex=1756
|RECORD=48|OwnerIndex=1756
|RECORD=1|LibReference=1029c3af85768c4190bb7ad29bc67b5|ComponentDescription=10kO ±1% 0.063W 0402 Thick Film Chip Resistor AEC-Q200 compliant|PartCount=2|DisplayModeCount=1|IndexInSheet=119|OwnerPartId=-1|Location.X=370|Location.Y=100|Orientation=2|CurrentPartId=1|LibraryPath=*|SourceLibraryName=Altium Content Vault|TargetFileName=*|AreaColor=11599871|Color=128|PartIDLocked=T|DesignItemId=CMP-26527-000128-1|AllPinCount=2
|RECORD=2|OwnerIndex=1759|OwnerPartId=1|Electrical=4|PinConglomerate=32|PinLength=20|Location.X=350|Location.Y=100|Name=1|Designator=1|PinPropagationDelay=0.000000E+000
|RECORD=2|OwnerIndex=1759|OwnerPartId=1|Electrical=4|PinConglomerate=34|PinLength=20|Location.X=320|Location.Y=100|Name=2|Designator=2|PinPropagationDelay=0.000000E+000
|RECORD=13|OwnerIndex=1759|IsNotAccesible=T|IndexInSheet=2|OwnerPartId=1|Location.X=350|Location.Y=100|Corner.X=347|Corner.Y=95|LineWidth=1|Color=16711680
|RECORD=13|OwnerIndex=1759|IsNotAccesible=T|IndexInSheet=3|OwnerPartId=1|Location.X=347|Location.Y=95|Corner.X=342|Corner.Y=105|LineWidth=1|Color=16711680
|RECORD=13|OwnerIndex=1759|IsNotAccesible=T|IndexInSheet=4|OwnerPartId=1|Location.X=342|Location.Y=105|Corner.X=337|Corner.Y=95|LineWidth=1|Color=16711680
|RECORD=13|OwnerIndex=1759|IsNotAccesible=T|IndexInSheet=5|OwnerPartId=1|Location.X=337|Location.Y=95|Corner.X=332|Corner.Y=105|LineWidth=1|Color=16711680
|RECORD=13|OwnerIndex=1759|IsNotAccesible=T|IndexInSheet=6|OwnerPartId=1|Location.X=332|Location.Y=105|Corner.X=327|Corner.Y=95|LineWidth=1|Color=16711680
|RECORD=13|OwnerIndex=1759|IsNotAccesible=T|IndexInSheet=7|OwnerPartId=1|Location.X=327|Location.Y=95|Corner.X=322|Corner.Y=105|LineWidth=1|Color=16711680
|RECORD=13|OwnerIndex=1759|IsNotAccesible=T|IndexInSheet=8|OwnerPartId=1|Location.X=322|Location.Y=105|Corner.X=320|Corner.Y=100|LineWidth=1|Color=16711680
|RECORD=13|OwnerIndex=1759|IsNotAccesible=T|IndexInSheet=9|OwnerPartId=1|Location.X=350|Location.Y=100|Corner.X=353|Corner.Y=100|LineWidth=1|Color=16711680
|RECORD=13|OwnerIndex=1759|IsNotAccesible=T|IndexInSheet=10|OwnerPartId=1|Location.X=320|Location.Y=100|Corner.X=317|Corner.Y=100|LineWidth=1|Color=16711680
|RECORD=41|OwnerIndex=1759|IndexInSheet=11|OwnerPartId=-1|Location.X=298|Location.Y=106|Color=8388608|FontID=1|IsHidden=T|Text=0.02inch|Name=Width
|RECORD=41|OwnerIndex=1759|IndexInSheet=12|OwnerPartId=-1|Location.X=298|Location.Y=106|Color=8388608|FontID=1|IsHidden=T|Text=0402|Name=Case/Package
|RECORD=41|OwnerIndex=1759|IndexInSheet=13|OwnerPartId=-1|Location.X=298|Location.Y=106|Color=8388608|FontID=1|IsHidden=T|Text=100ppm/°C|Name=Temperature Coefficient
|RECORD=41|OwnerIndex=1759|IndexInSheet=14|OwnerPartId=-1|Location.X=298|Location.Y=106|Color=8388608|FontID=1|IsHidden=T|Text=0.5mm|Name=Depth
|RECORD=41|OwnerIndex=1759|IndexInSheet=15|OwnerPartId=-1|Location.X=298|Location.Y=106|Color=8388608|FontID=1|IsHidden=T|Text=Thick Film|Name=Resistor Type
|RECORD=41|OwnerIndex=1759|IndexInSheet=16|OwnerPartId=-1|Location.X=298|Location.Y=106|Color=8388608|FontID=1|IsHidden=T|Text=RMCF|Name=Series
|RECORD=41|OwnerIndex=1759|IndexInSheet=17|OwnerPartId=-1|Location.X=298|Location.Y=106|Color=8388608|FontID=1|IsHidden=T|Text=1mm|Name=Length
|RECORD=41|OwnerIndex=1759|IndexInSheet=18|OwnerPartId=-1|Location.X=298|Location.Y=106|Color=8388608|FontID=1|IsHidden=T|Text=62.5mW|Name=Power Rating
|RECORD=41|OwnerIndex=1759|IndexInSheet=19|OwnerPartId=-1|Location.X=298|Location.Y=106|Color=8388608|FontID=1|IsHidden=T|Text=10kR|Name=Resistance
|RECORD=41|OwnerIndex=1759|IndexInSheet=20|OwnerPartId=-1|Location.X=298|Location.Y=106|Color=8388608|FontID=1|IsHidden=T|Text=Tin|Name=Contact Plating
|RECORD=41|OwnerIndex=1759|IndexInSheet=21|OwnerPartId=-1|Location.X=298|Location.Y=106|Color=8388608|FontID=1|IsHidden=T|Text=1%|Name=Tolerance
|RECORD=41|OwnerIndex=1759|IndexInSheet=22|OwnerPartId=-1|Location.X=298|Location.Y=106|Color=8388608|FontID=1|IsHidden=T|Text=2|Name=Number of Terminations
|RECORD=41|OwnerIndex=1759|IndexInSheet=23|OwnerPartId=-1|Location.X=298|Location.Y=106|Color=8388608|FontID=1|IsHidden=T|Text=0.016inch|Name=Height
|RECORD=41|OwnerIndex=1759|IndexInSheet=24|OwnerPartId=-1|Location.X=298|Location.Y=106|Color=8388608|FontID=1|IsHidden=T|Text=Not|Name=Military Standard
|RECORD=41|OwnerIndex=1759|IndexInSheet=25|OwnerPartId=-1|Location.X=298|Location.Y=106|Color=8388608|FontID=1|IsHidden=T|Text=0402|Name=Case Code (Imperial)
|RECORD=41|OwnerIndex=1759|IndexInSheet=26|OwnerPartId=-1|Location.X=298|Location.Y=106|Color=8388608|FontID=1|IsHidden=T|Text=63mW|Name=Max Power Dissipation
|RECORD=41|OwnerIndex=1759|IndexInSheet=27|OwnerPartId=-1|Location.X=298|Location.Y=106|Color=8388608|FontID=1|IsHidden=T|Text=0402|Name=Size Code
|RECORD=41|OwnerIndex=1759|IndexInSheet=28|OwnerPartId=-1|Location.X=298|Location.Y=106|Color=8388608|FontID=1|IsHidden=T|Text=Rectangular|Name=Construction
|RECORD=41|OwnerIndex=1759|IndexInSheet=29|OwnerPartId=-1|Location.X=298|Location.Y=106|Color=8388608|FontID=1|IsHidden=T|Text=No|Name=Radiation Hardening
|RECORD=41|OwnerIndex=1759|IndexInSheet=30|OwnerPartId=-1|Location.X=298|Location.Y=106|Color=8388608|FontID=1|IsHidden=T|Text=Yes|Name=RoHS Compliant
|RECORD=41|OwnerIndex=1759|IndexInSheet=31|OwnerPartId=-1|Location.X=298|Location.Y=106|Color=8388608|FontID=1|IsHidden=T|Text=1005|Name=Case Code (Metric)
|RECORD=41|OwnerIndex=1759|IndexInSheet=32|OwnerPartId=-1|Location.X=298|Location.Y=106|Color=8388608|FontID=1|IsHidden=T|Text=Tape and Reel|Name=Packaging
|RECORD=41|OwnerIndex=1759|IndexInSheet=33|OwnerPartId=-1|Location.X=298|Location.Y=106|Color=8388608|FontID=1|IsHidden=T|Text=Lead Free|Name=Lead Free
|RECORD=41|OwnerIndex=1759|IndexInSheet=34|OwnerPartId=-1|Location.X=298|Location.Y=106|Color=8388608|FontID=1|IsHidden=T|Text=-55°C|Name=Min Operating Temperature
|RECORD=41|OwnerIndex=1759|IndexInSheet=35|OwnerPartId=-1|Location.X=298|Location.Y=106|Color=8388608|FontID=1|IsHidden=T|Text=155°C|Name=Max Operating Temperature
|RECORD=41|OwnerIndex=1759|IndexInSheet=36|OwnerPartId=-1|Location.X=298|Location.Y=106|Color=8388608|FontID=1|IsHidden=T|Text=Surface Mount|Name=Mount
|RECORD=41|OwnerIndex=1759|IndexInSheet=37|OwnerPartId=-1|Location.X=298|Location.Y=106|Color=8388608|FontID=1|IsHidden=T|Text=Automotive AEC-Q200|Name=Features
|RECORD=34|OwnerIndex=1759|IndexInSheet=-1|OwnerPartId=-1|Location.X=316|Location.Y=106|Color=8388608|FontID=1|Text=R6|Name=Designator|ReadOnlyState=1
|RECORD=41|OwnerIndex=1759|IndexInSheet=-1|OwnerPartId=1|Location.X=316|Location.Y=84|Color=8388608|FontID=1|Text=10k|Name=Comment
|RECORD=44|OwnerIndex=1759
|RECORD=45|OwnerIndex=1802|IndexInSheet=-1|UseComponentLibrary=T|ModelName=FP-RMCF0402-IPC_C|ModelType=PCBLIB|DatafileCount=1|ModelDatafileEntity0=FP-RMCF0402-IPC_C|ModelDatafileKind0=PCBLib|IsCurrent=T|DatalinksLocked=T|DatabaseDatalinksLocked=T
|RECORD=46|OwnerIndex=1803
|RECORD=48|OwnerIndex=1803
|RECORD=45|OwnerIndex=1802|IndexInSheet=-1|UseComponentLibrary=T|ModelName=FP-RMCF0402-MFG|ModelType=PCBLIB|DatafileCount=1|ModelDatafileEntity0=FP-RMCF0402-MFG|ModelDatafileKind0=PCBLib|DatalinksLocked=T|DatabaseDatalinksLocked=T
|RECORD=46|OwnerIndex=1806
|RECORD=48|OwnerIndex=1806
|RECORD=45|OwnerIndex=1802|IndexInSheet=-1|UseComponentLibrary=T|ModelName=FP-RMCF0402-IPC_A|ModelType=PCBLIB|DatafileCount=1|ModelDatafileEntity0=FP-RMCF0402-IPC_A|ModelDatafileKind0=PCBLib|DatalinksLocked=T|DatabaseDatalinksLocked=T
|RECORD=46|OwnerIndex=1809
|RECORD=48|OwnerIndex=1809
|RECORD=45|OwnerIndex=1802|IndexInSheet=-1|UseComponentLibrary=T|ModelName=FP-RMCF0402-IPC_B|ModelType=PCBLIB|DatafileCount=1|ModelDatafileEntity0=FP-RMCF0402-IPC_B|ModelDatafileKind0=PCBLib|DatalinksLocked=T|DatabaseDatalinksLocked=T
|RECORD=46|OwnerIndex=1812
|RECORD=48|OwnerIndex=1812
|RECORD=25|IndexInSheet=120|OwnerPartId=-1|Location.X=40|Location.Y=400|Color=128|FontID=1|Text=TXD
|RECORD=25|IndexInSheet=121|OwnerPartId=-1|Location.X=40|Location.Y=470|Color=128|FontID=1|Text=RXD_IN
|RECORD=25|IndexInSheet=122|OwnerPartId=-1|Location.X=220|Location.Y=400|Justification=2|Color=128|FontID=1|Text=TXD_OUT
|RECORD=25|IndexInSheet=123|OwnerPartId=-1|Location.X=220|Location.Y=470|Justification=2|Color=128|FontID=1|Text=RXD
|RECORD=1|LibReference=LED_Green_300mil|ComponentDescription=LED, GREEN, 574NM, 20MA, 20MCD MIN, 2.5VF MAX, 0603, 1.10MM T|PartCount=2|DisplayModeCount=1|IndexInSheet=124|OwnerPartId=-1|Location.X=270|Location.Y=320|Orientation=2|CurrentPartId=1|LibraryPath=*|SourceLibraryName=RL Research Altium Server|TargetFileName=*|AreaColor=11599871|Color=128|PartIDLocked=T|DesignItemId=LED-CMP-00021-2|AllPinCount=2
|RECORD=2|OwnerIndex=1819|OwnerPartId=1|FormalType=1|Electrical=4|PinConglomerate=35|PinLength=10|Location.X=270|Location.Y=330|Name=Cathode|Designator=K|SwapIDPart=0|PinName_PositionConglomerate=16|Name_CustomFontID=16|PinDesignator_PositionConglomerate=16|Designator_CustomFontID=16|PinPropagationDelay=0.000000E+000
|RECORD=2|OwnerIndex=1819|OwnerPartId=1|FormalType=1|Electrical=4|PinConglomerate=33|PinLength=10|Location.X=270|Location.Y=340|Name=Anode|Designator=A|SwapIDPart=0|PinName_PositionConglomerate=16|Name_CustomFontID=16|PinDesignator_PositionConglomerate=16|Designator_CustomFontID=16|PinPropagationDelay=0.000000E+000
|RECORD=6|OwnerIndex=1819|IsNotAccesible=T|IndexInSheet=2|OwnerPartId=1|LineWidth=1|Color=65280|LocationCount=6|X1=264|Y1=334|X2=261|Y2=331|X3=260|Y3=332|X4=259|Y4=329|X5=262|Y5=330|X6=261|Y6=331
|RECORD=6|OwnerIndex=1819|IsNotAccesible=T|IndexInSheet=3|OwnerPartId=1|LineWidth=1|Color=65280|LocationCount=6|X1=263|Y1=338|X2=260|Y2=335|X3=259|Y3=336|X4=258|Y4=333|X5=261|Y5=334|X6=260|Y6=335
|RECORD=3|OwnerIndex=1819|IsNotAccesible=T|IndexInSheet=4|OwnerPartId=1|Symbol=33|Location.X=270|Location.Y=330|ScaleFactor=10|Orientation=3|LineWidth=1|Color=65280
|RECORD=6|OwnerIndex=1819|IsNotAccesible=T|IndexInSheet=5|OwnerPartId=1|LineWidth=1|Color=65280|LocationCount=2|X1=273|Y1=330|X2=267|Y2=330
|RECORD=6|OwnerIndex=1819|IsNotAccesible=T|IndexInSheet=6|OwnerPartId=1|LineWidth=1|Color=65280|LocationCount=2|X1=270|Y1=340|X2=270|Y2=336
|RECORD=41|OwnerIndex=1819|IndexInSheet=7|OwnerPartId=-1|Location.X=257|Location.Y=352|Color=8388608|FontID=1|IsHidden=T|Text=Clear|Name=Lens Transparency
|RECORD=41|OwnerIndex=1819|IndexInSheet=8|OwnerPartId=-1|Location.X=257|Location.Y=352|Color=8388608|FontID=1|IsHidden=T|Text=50mcd|Name=Millicandela Rating
|RECORD=41|OwnerIndex=1819|IndexInSheet=9|OwnerPartId=-1|Location.X=257|Location.Y=352|Color=8388608|FontID=1|IsHidden=T|Name=Type
|RECORD=41|OwnerIndex=1819|IndexInSheet=10|OwnerPartId=-1|Location.X=257|Location.Y=352|Color=8388608|FontID=1|IsHidden=T|Name=Wavelength
|RECORD=41|OwnerIndex=1819|IndexInSheet=11|OwnerPartId=-1|Location.X=257|Location.Y=352|Color=8388608|FontID=1|IsHidden=T|Text=2.2V|Name=Voltage - Forward (Vf) (Typ)
|RECORD=41|OwnerIndex=1819|IndexInSheet=12|OwnerPartId=-1|Location.X=257|Location.Y=352|Color=8388608|FontID=1|IsHidden=T|Text=1.60mm L x 0.80mm W|Name=Size / Dimension
|RECORD=41|OwnerIndex=1819|IndexInSheet=13|OwnerPartId=-1|Location.X=257|Location.Y=352|Color=8388608|FontID=1|IsHidden=T|Text=85°C|Name=Max Operating Temperature
|RECORD=41|OwnerIndex=1819|IndexInSheet=14|OwnerPartId=-1|Location.X=257|Location.Y=352|Color=8388608|FontID=1|IsHidden=T|Text=-40°C|Name=Min Operating Temperature
|RECORD=41|OwnerIndex=1819|IndexInSheet=15|OwnerPartId=-1|Location.X=257|Location.Y=352|Color=8388608|FontID=1|IsHidden=T|Name=Series
|RECORD=41|OwnerIndex=1819|IndexInSheet=16|OwnerPartId=-1|Location.X=257|Location.Y=352|Color=8388608|FontID=1|IsHidden=T|Name=Character Format
|RECORD=41|OwnerIndex=1819|IndexInSheet=17|OwnerPartId=-1|Location.X=257|Location.Y=352|Color=8388608|FontID=1|IsHidden=T|Name=Number of Characters
|RECORD=41|OwnerIndex=1819|IndexInSheet=18|OwnerPartId=-1|Location.X=257|Location.Y=352|Color=8388608|FontID=1|IsHidden=T|Text=Independent|Name=Configuration
|RECORD=41|OwnerIndex=1819|IndexInSheet=19|OwnerPartId=-1|Location.X=257|Location.Y=352|Color=8388608|FontID=1|IsHidden=T|Text=838-00422-00|Name=Internal Part Number
|RECORD=41|OwnerIndex=1819|IndexInSheet=20|OwnerPartId=-1|Location.X=257|Location.Y=352|Color=8388608|FontID=1|IsHidden=T|Name=Applications
|RECORD=41|OwnerIndex=1819|IndexInSheet=21|OwnerPartId=-1|Location.X=257|Location.Y=352|Color=8388608|FontID=1|IsHidden=T|Name=Connector Type
|RECORD=41|OwnerIndex=1819|IndexInSheet=22|OwnerPartId=-1|Location.X=257|Location.Y=352|Color=8388608|FontID=1|IsHidden=T|Name=Current - DC Forward (If) (Max)
|RECORD=41|OwnerIndex=1819|IndexInSheet=23|OwnerPartId=-1|Location.X=257|Location.Y=352|Color=8388608|FontID=1|IsHidden=T|Text=120°|Name=Viewing Angle
|RECORD=41|OwnerIndex=1819|IndexInSheet=24|OwnerPartId=-1|Location.X=257|Location.Y=352|Color=8388608|FontID=1|IsHidden=T|Name=Radiant Intensity (Ie) Min @ If
|RECORD=41|OwnerIndex=1819|IndexInSheet=25|OwnerPartId=-1|Location.X=257|Location.Y=352|Color=8388608|FontID=1|IsHidden=T|Text=LED Indication - Discrete|Name=Category
|RECORD=41|OwnerIndex=1819|IndexInSheet=26|OwnerPartId=-1|Location.X=257|Location.Y=352|Color=8388608|FontID=1|IsHidden=T|Name=Display Mode
|RECORD=41|OwnerIndex=1819|IndexInSheet=27|OwnerPartId=-1|Location.X=257|Location.Y=352|Color=8388608|FontID=1|IsHidden=T|Text=Green|Name=Lens Color
|RECORD=41|OwnerIndex=1819|IndexInSheet=28|OwnerPartId=-1|Location.X=257|Location.Y=352|Color=8388608|FontID=1|IsHidden=T|Text=0603 (1608 Metric)|Name=Case/Package
|RECORD=41|OwnerIndex=1819|IndexInSheet=29|OwnerPartId=-1|Location.X=257|Location.Y=352|Color=8388608|FontID=1|IsHidden=T|Name=Voltage - Supply
|RECORD=41|OwnerIndex=1819|IndexInSheet=30|OwnerPartId=-1|Location.X=257|Location.Y=352|Color=8388608|FontID=1|IsHidden=T|Text=20mA|Name=Current - Test
|RECORD=41|OwnerIndex=1819|IndexInSheet=31|OwnerPartId=-1|Location.X=257|Location.Y=352|Color=8388608|FontID=1|IsHidden=T|Name=Data Rate
|RECORD=41|OwnerIndex=1819|IndexInSheet=32|OwnerPartId=-1|Location.X=257|Location.Y=352|Color=8388608|FontID=1|IsHidden=T|Text=574nm|Name=Wavelength - Peak
|RECORD=41|OwnerIndex=1819|IndexInSheet=33|OwnerPartId=-1|Location.X=257|Location.Y=352|Color=8388608|FontID=1|IsHidden=T|Text=1.20mm x 0.80mm|Name=Lens Size
|RECORD=41|OwnerIndex=1819|IndexInSheet=34|OwnerPartId=-1|Location.X=257|Location.Y=352|Color=8388608|FontID=1|IsHidden=T|Name=Part Status
|RECORD=41|OwnerIndex=1819|IndexInSheet=35|OwnerPartId=-1|Location.X=257|Location.Y=352|Color=8388608|FontID=1|IsHidden=T|Text=Surface Mount|Name=Mounting Type
|RECORD=41|OwnerIndex=1819|IndexInSheet=36|OwnerPartId=-1|Location.X=257|Location.Y=352|Color=8388608|FontID=1|IsHidden=T|Text=Yes|Name=RoHS
|RECORD=41|OwnerIndex=1819|IndexInSheet=37|OwnerPartId=-1|Location.X=257|Location.Y=352|Color=8388608|FontID=1|IsHidden=T|Text=Lumex Opto/Components Inc.|Name=Manufacturer
|RECORD=41|OwnerIndex=1819|IndexInSheet=38|OwnerPartId=-1|Location.X=257|Location.Y=352|Color=8388608|FontID=1|IsHidden=T|Name=Wavelength - Dominant
|RECORD=41|OwnerIndex=1819|IndexInSheet=39|OwnerPartId=-1|Location.X=257|Location.Y=352|Color=8388608|FontID=1|IsHidden=T|Name=Features
|RECORD=41|OwnerIndex=1819|IndexInSheet=40|OwnerPartId=-1|Location.X=257|Location.Y=352|Color=8388608|FontID=1|IsHidden=T|Text=1.10mm|Name=Height (Max)
|RECORD=41|OwnerIndex=1819|IndexInSheet=41|OwnerPartId=-1|Location.X=257|Location.Y=352|Color=8388608|FontID=1|IsHidden=T|Text=Digikey|Name=Supplier 1
|RECORD=41|OwnerIndex=1819|IndexInSheet=42|OwnerPartId=-1|Location.X=257|Location.Y=352|Color=8388608|FontID=1|IsHidden=T|Name=Attenuation Value
|RECORD=41|OwnerIndex=1819|IndexInSheet=43|OwnerPartId=-1|Location.X=257|Location.Y=352|Color=8388608|FontID=1|IsHidden=T|Name=Display Format
|RECORD=41|OwnerIndex=1819|IndexInSheet=44|OwnerPartId=-1|Location.X=257|Location.Y=352|Color=8388608|FontID=1|IsHidden=T|Name=Current - Supply
|RECORD=41|OwnerIndex=1819|IndexInSheet=45|OwnerPartId=-1|Location.X=257|Location.Y=352|Color=8388608|FontID=1|IsHidden=T|Text=Rectangle with Flat Top|Name=Lens Style
|RECORD=41|OwnerIndex=1819|IndexInSheet=46|OwnerPartId=-1|Location.X=257|Location.Y=352|Color=8388608|FontID=1|IsHidden=T|Name=Viewing Area
|RECORD=41|OwnerIndex=1819|IndexInSheet=47|OwnerPartId=-1|Location.X=274|Location.Y=321|Color=8388608|FontID=1|Text=Green|Name=Color
|RECORD=41|OwnerIndex=1819|IndexInSheet=48|OwnerPartId=-1|Location.X=257|Location.Y=352|Color=8388608|FontID=2|IsHidden=T|Text=https://www.digikey.com/en/products/detail/lumex-opto-components-inc/SML-LXFM0603SUGCTR/7364547?s=N4IgTCBcDaIMoFkAyBaJANAYggDANhwGY4BVAcQGEAVAJRAF0BfIA|Name=Datasheet URL
|RECORD=41|OwnerIndex=1819|IndexInSheet=49|OwnerPartId=-1|Location.X=257|Location.Y=352|Color=8388608|FontID=1|IsHidden=T|Name=Orientation
|RECORD=41|OwnerIndex=1819|IndexInSheet=50|OwnerPartId=-1|Location.X=257|Location.Y=352|Color=8388608|FontID=1|IsHidden=T|Name=Display Type
|RECORD=41|OwnerIndex=1819|IndexInSheet=51|OwnerPartId=-1|Location.X=257|Location.Y=352|Color=8388608|FontID=1|IsHidden=T|Text=67-2320-1-ND|Name=Supplier Part Number 1
|RECORD=41|OwnerIndex=1819|IndexInSheet=52|OwnerPartId=-1|Location.X=257|Location.Y=352|Color=8388608|FontID=1|IsHidden=T|Text=SML-LXFM0603SUGCTR|Name=Manufacturer Part Number
|RECORD=41|OwnerIndex=1819|IndexInSheet=53|OwnerPartId=-1|Location.X=257|Location.Y=352|Color=8388608|FontID=1|IsHidden=T|Name=Backlight
|RECORD=34|OwnerIndex=1819|IndexInSheet=-1|OwnerPartId=-1|Location.X=274|Location.Y=331|Color=8388608|FontID=1|Text=DS1|Name=Designator|ReadOnlyState=1
|RECORD=41|OwnerIndex=1819|IndexInSheet=-1|OwnerPartId=-1|Location.X=257|Location.Y=352|Color=8388608|FontID=1|IsHidden=T|Text=Lumex_SML-LXFM0603SUGCTR|Name=Comment
|RECORD=44|OwnerIndex=1819
|RECORD=45|OwnerIndex=1878|IndexInSheet=-1|Description=LED, Body 1.6x0.8mm, Height 1.10mm, LXFM0603-GR|UseComponentLibrary=T|ModelName=LEDS160X80X110-2N_LXFM0603-GR|ModelType=PCBLIB|DatafileCount=1|ModelDatafileEntity0=LEDS160X80X110-2N_LXFM0603-GR|ModelDatafileKind0=PCBLib|IsCurrent=T|DatalinksLocked=T|DatabaseDatalinksLocked=T
|RECORD=46|OwnerIndex=1879
|RECORD=47|OwnerIndex=1880|DesImpCount=1|DesImp0=null
|RECORD=48|OwnerIndex=1879
|RECORD=41|OwnerIndex=1882|IndexInSheet=-1|OwnerPartId=-1|Color=8388608|FontID=1|IsHidden=T|Text=2D|Name=Available Preview Images
|RECORD=1|LibReference=1029c3af85768c4190bb7ad29bc67b5|ComponentDescription=10kO ±1% 0.063W 0402 Thick Film Chip Resistor AEC-Q200 compliant|PartCount=2|DisplayModeCount=1|IndexInSheet=125|OwnerPartId=-1|Location.X=270|Location.Y=250|Orientation=1|CurrentPartId=1|LibraryPath=*|SourceLibraryName=Altium Content Vault|TargetFileName=*|AreaColor=11599871|Color=128|PartIDLocked=T|DesignItemId=CMP-26527-000128-1|AllPinCount=2
|RECORD=2|OwnerIndex=1884|OwnerPartId=1|Electrical=4|PinConglomerate=35|PinLength=20|Location.X=270|Location.Y=270|Name=1|Designator=1|PinPropagationDelay=0.000000E+000
|RECORD=2|OwnerIndex=1884|OwnerPartId=1|Electrical=4|PinConglomerate=33|PinLength=20|Location.X=270|Location.Y=300|Name=2|Designator=2|PinPropagationDelay=0.000000E+000
|RECORD=13|OwnerIndex=1884|IsNotAccesible=T|IndexInSheet=2|OwnerPartId=1|Location.X=270|Location.Y=270|Corner.X=265|Corner.Y=273|LineWidth=1|Color=16711680
|RECORD=13|OwnerIndex=1884|IsNotAccesible=T|IndexInSheet=3|OwnerPartId=1|Location.X=265|Location.Y=273|Corner.X=275|Corner.Y=278|LineWidth=1|Color=16711680
|RECORD=13|OwnerIndex=1884|IsNotAccesible=T|IndexInSheet=4|OwnerPartId=1|Location.X=275|Location.Y=278|Corner.X=265|Corner.Y=283|LineWidth=1|Color=16711680
|RECORD=13|OwnerIndex=1884|IsNotAccesible=T|IndexInSheet=5|OwnerPartId=1|Location.X=265|Location.Y=283|Corner.X=275|Corner.Y=288|LineWidth=1|Color=16711680
|RECORD=13|OwnerIndex=1884|IsNotAccesible=T|IndexInSheet=6|OwnerPartId=1|Location.X=275|Location.Y=288|Corner.X=265|Corner.Y=293|LineWidth=1|Color=16711680
|RECORD=13|OwnerIndex=1884|IsNotAccesible=T|IndexInSheet=7|OwnerPartId=1|Location.X=265|Location.Y=293|Corner.X=275|Corner.Y=298|LineWidth=1|Color=16711680
|RECORD=13|OwnerIndex=1884|IsNotAccesible=T|IndexInSheet=8|OwnerPartId=1|Location.X=275|Location.Y=298|Corner.X=270|Corner.Y=300|LineWidth=1|Color=16711680
|RECORD=13|OwnerIndex=1884|IsNotAccesible=T|IndexInSheet=9|OwnerPartId=1|Location.X=270|Location.Y=270|Corner.X=270|Corner.Y=267|LineWidth=1|Color=16711680
|RECORD=13|OwnerIndex=1884|IsNotAccesible=T|IndexInSheet=10|OwnerPartId=1|Location.X=270|Location.Y=300|Corner.X=270|Corner.Y=303|LineWidth=1|Color=16711680
|RECORD=41|OwnerIndex=1884|IndexInSheet=11|OwnerPartId=-1|Location.X=264|Location.Y=322|Color=8388608|FontID=1|IsHidden=T|Text=0.02inch|Name=Width
|RECORD=41|OwnerIndex=1884|IndexInSheet=12|OwnerPartId=-1|Location.X=264|Location.Y=322|Color=8388608|FontID=1|IsHidden=T|Text=0402|Name=Case/Package
|RECORD=41|OwnerIndex=1884|IndexInSheet=13|OwnerPartId=-1|Location.X=264|Location.Y=322|Color=8388608|FontID=1|IsHidden=T|Text=100ppm/°C|Name=Temperature Coefficient
|RECORD=41|OwnerIndex=1884|IndexInSheet=14|OwnerPartId=-1|Location.X=264|Location.Y=322|Color=8388608|FontID=1|IsHidden=T|Text=0.5mm|Name=Depth
|RECORD=41|OwnerIndex=1884|IndexInSheet=15|OwnerPartId=-1|Location.X=264|Location.Y=322|Color=8388608|FontID=1|IsHidden=T|Text=Thick Film|Name=Resistor Type
|RECORD=41|OwnerIndex=1884|IndexInSheet=16|OwnerPartId=-1|Location.X=264|Location.Y=322|Color=8388608|FontID=1|IsHidden=T|Text=RMCF|Name=Series
|RECORD=41|OwnerIndex=1884|IndexInSheet=17|OwnerPartId=-1|Location.X=264|Location.Y=322|Color=8388608|FontID=1|IsHidden=T|Text=1mm|Name=Length
|RECORD=41|OwnerIndex=1884|IndexInSheet=18|OwnerPartId=-1|Location.X=264|Location.Y=322|Color=8388608|FontID=1|IsHidden=T|Text=62.5mW|Name=Power Rating
|RECORD=41|OwnerIndex=1884|IndexInSheet=19|OwnerPartId=-1|Location.X=264|Location.Y=322|Color=8388608|FontID=1|IsHidden=T|Text=10kR|Name=Resistance
|RECORD=41|OwnerIndex=1884|IndexInSheet=20|OwnerPartId=-1|Location.X=264|Location.Y=322|Color=8388608|FontID=1|IsHidden=T|Text=Tin|Name=Contact Plating
|RECORD=41|OwnerIndex=1884|IndexInSheet=21|OwnerPartId=-1|Location.X=264|Location.Y=322|Color=8388608|FontID=1|IsHidden=T|Text=1%|Name=Tolerance
|RECORD=41|OwnerIndex=1884|IndexInSheet=22|OwnerPartId=-1|Location.X=264|Location.Y=322|Color=8388608|FontID=1|IsHidden=T|Text=2|Name=Number of Terminations
|RECORD=41|OwnerIndex=1884|IndexInSheet=23|OwnerPartId=-1|Location.X=264|Location.Y=322|Color=8388608|FontID=1|IsHidden=T|Text=0.016inch|Name=Height
|RECORD=41|OwnerIndex=1884|IndexInSheet=24|OwnerPartId=-1|Location.X=264|Location.Y=322|Color=8388608|FontID=1|IsHidden=T|Text=Not|Name=Military Standard
|RECORD=41|OwnerIndex=1884|IndexInSheet=25|OwnerPartId=-1|Location.X=264|Location.Y=322|Color=8388608|FontID=1|IsHidden=T|Text=0402|Name=Case Code (Imperial)
|RECORD=41|OwnerIndex=1884|IndexInSheet=26|OwnerPartId=-1|Location.X=264|Location.Y=322|Color=8388608|FontID=1|IsHidden=T|Text=63mW|Name=Max Power Dissipation
|RECORD=41|OwnerIndex=1884|IndexInSheet=27|OwnerPartId=-1|Location.X=264|Location.Y=322|Color=8388608|FontID=1|IsHidden=T|Text=0402|Name=Size Code
|RECORD=41|OwnerIndex=1884|IndexInSheet=28|OwnerPartId=-1|Location.X=264|Location.Y=322|Color=8388608|FontID=1|IsHidden=T|Text=Rectangular|Name=Construction
|RECORD=41|OwnerIndex=1884|IndexInSheet=29|OwnerPartId=-1|Location.X=264|Location.Y=322|Color=8388608|FontID=1|IsHidden=T|Text=No|Name=Radiation Hardening
|RECORD=41|OwnerIndex=1884|IndexInSheet=30|OwnerPartId=-1|Location.X=264|Location.Y=322|Color=8388608|FontID=1|IsHidden=T|Text=Yes|Name=RoHS Compliant
|RECORD=41|OwnerIndex=1884|IndexInSheet=31|OwnerPartId=-1|Location.X=264|Location.Y=322|Color=8388608|FontID=1|IsHidden=T|Text=1005|Name=Case Code (Metric)
|RECORD=41|OwnerIndex=1884|IndexInSheet=32|OwnerPartId=-1|Location.X=264|Location.Y=322|Color=8388608|FontID=1|IsHidden=T|Text=Tape and Reel|Name=Packaging
|RECORD=41|OwnerIndex=1884|IndexInSheet=33|OwnerPartId=-1|Location.X=264|Location.Y=322|Color=8388608|FontID=1|IsHidden=T|Text=Lead Free|Name=Lead Free
|RECORD=41|OwnerIndex=1884|IndexInSheet=34|OwnerPartId=-1|Location.X=264|Location.Y=322|Color=8388608|FontID=1|IsHidden=T|Text=-55°C|Name=Min Operating Temperature
|RECORD=41|OwnerIndex=1884|IndexInSheet=35|OwnerPartId=-1|Location.X=264|Location.Y=322|Color=8388608|FontID=1|IsHidden=T|Text=155°C|Name=Max Operating Temperature
|RECORD=41|OwnerIndex=1884|IndexInSheet=36|OwnerPartId=-1|Location.X=264|Location.Y=322|Color=8388608|FontID=1|IsHidden=T|Text=Surface Mount|Name=Mount
|RECORD=41|OwnerIndex=1884|IndexInSheet=37|OwnerPartId=-1|Location.X=264|Location.Y=322|Color=8388608|FontID=1|IsHidden=T|Text=Automotive AEC-Q200|Name=Features
|RECORD=34|OwnerIndex=1884|IndexInSheet=-1|OwnerPartId=-1|Location.X=276|Location.Y=294|Color=8388608|FontID=1|Text=R4|Name=Designator|ReadOnlyState=1
|RECORD=41|OwnerIndex=1884|IndexInSheet=-1|OwnerPartId=1|Location.X=276|Location.Y=284|Color=8388608|FontID=1|Text=10k|Name=Comment
|RECORD=44|OwnerIndex=1884
|RECORD=45|OwnerIndex=1927|IndexInSheet=-1|UseComponentLibrary=T|ModelName=FP-RMCF0402-IPC_C|ModelType=PCBLIB|DatafileCount=1|ModelDatafileEntity0=FP-RMCF0402-IPC_C|ModelDatafileKind0=PCBLib|IsCurrent=T|DatalinksLocked=T|DatabaseDatalinksLocked=T
|RECORD=46|OwnerIndex=1928
|RECORD=48|OwnerIndex=1928
|RECORD=45|OwnerIndex=1927|IndexInSheet=-1|UseComponentLibrary=T|ModelName=FP-RMCF0402-MFG|ModelType=PCBLIB|DatafileCount=1|ModelDatafileEntity0=FP-RMCF0402-MFG|ModelDatafileKind0=PCBLib|DatalinksLocked=T|DatabaseDatalinksLocked=T
|RECORD=46|OwnerIndex=1931
|RECORD=48|OwnerIndex=1931
|RECORD=45|OwnerIndex=1927|IndexInSheet=-1|UseComponentLibrary=T|ModelName=FP-RMCF0402-IPC_A|ModelType=PCBLIB|DatafileCount=1|ModelDatafileEntity0=FP-RMCF0402-IPC_A|ModelDatafileKind0=PCBLib|DatalinksLocked=T|DatabaseDatalinksLocked=T
|RECORD=46|OwnerIndex=1934
|RECORD=48|OwnerIndex=1934
|RECORD=45|OwnerIndex=1927|IndexInSheet=-1|UseComponentLibrary=T|ModelName=FP-RMCF0402-IPC_B|ModelType=PCBLIB|DatafileCount=1|ModelDatafileEntity0=FP-RMCF0402-IPC_B|ModelDatafileKind0=PCBLib|DatalinksLocked=T|DatabaseDatalinksLocked=T
|RECORD=46|OwnerIndex=1937
|RECORD=48|OwnerIndex=1937
|RECORD=17|IndexInSheet=126|OwnerPartId=-1|Style=4|ShowNetName=F|Location.X=270|Location.Y=250|Orientation=3|Color=128|FontID=1|Text=GND
|RECORD=25|IndexInSheet=127|OwnerPartId=-1|Location.X=300|Location.Y=350|Justification=2|Color=128|FontID=1|Text=TP2
|RECORD=14|IndexInSheet=128|OwnerPartId=-1|Location.X=240|Location.Y=210|Corner.X=440|Corner.Y=370|Color=128|AreaColor=11599871
|RECORD=4|IndexInSheet=129|OwnerPartId=-1|Location.X=240|Location.Y=370|Color=8388608|FontID=15|Text=TP2 Indicator LED
|RECORD=1|LibReference=1029c3af85768c4190bb7ad29bc67b5|ComponentDescription=1kO ±1% 0.063W 0402 Thick Film Chip Resistor AEC-Q200 compliant|PartCount=2|DisplayModeCount=1|IndexInSheet=130|OwnerPartId=-1|Location.X=270|Location.Y=410|Orientation=1|CurrentPartId=1|LibraryPath=*|SourceLibraryName=Altium Content Vault|TargetFileName=*|AreaColor=11599871|Color=128|PartIDLocked=T|DesignItemId=CMP-26527-000026-1|AllPinCount=2
|RECORD=2|OwnerIndex=1944|OwnerPartId=1|Electrical=4|PinConglomerate=35|PinLength=20|Location.X=270|Location.Y=430|Name=1|Designator=1|PinPropagationDelay=0.000000E+000
|RECORD=2|OwnerIndex=1944|OwnerPartId=1|Electrical=4|PinConglomerate=33|PinLength=20|Location.X=270|Location.Y=460|Name=2|Designator=2|PinPropagationDelay=0.000000E+000
|RECORD=13|OwnerIndex=1944|IsNotAccesible=T|IndexInSheet=2|OwnerPartId=1|Location.X=270|Location.Y=430|Corner.X=265|Corner.Y=433|LineWidth=1|Color=16711680
|RECORD=13|OwnerIndex=1944|IsNotAccesible=T|IndexInSheet=3|OwnerPartId=1|Location.X=265|Location.Y=433|Corner.X=275|Corner.Y=438|LineWidth=1|Color=16711680
|RECORD=13|OwnerIndex=1944|IsNotAccesible=T|IndexInSheet=4|OwnerPartId=1|Location.X=275|Location.Y=438|Corner.X=265|Corner.Y=443|LineWidth=1|Color=16711680
|RECORD=13|OwnerIndex=1944|IsNotAccesible=T|IndexInSheet=5|OwnerPartId=1|Location.X=265|Location.Y=443|Corner.X=275|Corner.Y=448|LineWidth=1|Color=16711680
|RECORD=13|OwnerIndex=1944|IsNotAccesible=T|IndexInSheet=6|OwnerPartId=1|Location.X=275|Location.Y=448|Corner.X=265|Corner.Y=453|LineWidth=1|Color=16711680
|RECORD=13|OwnerIndex=1944|IsNotAccesible=T|IndexInSheet=7|OwnerPartId=1|Location.X=265|Location.Y=453|Corner.X=275|Corner.Y=458|LineWidth=1|Color=16711680
|RECORD=13|OwnerIndex=1944|IsNotAccesible=T|IndexInSheet=8|OwnerPartId=1|Location.X=275|Location.Y=458|Corner.X=270|Corner.Y=460|LineWidth=1|Color=16711680
|RECORD=13|OwnerIndex=1944|IsNotAccesible=T|IndexInSheet=9|OwnerPartId=1|Location.X=270|Location.Y=430|Corner.X=270|Corner.Y=427|LineWidth=1|Color=16711680
|RECORD=13|OwnerIndex=1944|IsNotAccesible=T|IndexInSheet=10|OwnerPartId=1|Location.X=270|Location.Y=460|Corner.X=270|Corner.Y=463|LineWidth=1|Color=16711680
|RECORD=41|OwnerIndex=1944|IndexInSheet=11|OwnerPartId=-1|Location.X=264|Location.Y=482|Color=8388608|FontID=1|IsHidden=T|Text=1mm|Name=Length
|RECORD=41|OwnerIndex=1944|IndexInSheet=12|OwnerPartId=-1|Location.X=264|Location.Y=482|Color=8388608|FontID=1|IsHidden=T|Text=Yes|Name=RoHS Compliant
|RECORD=41|OwnerIndex=1944|IndexInSheet=13|OwnerPartId=-1|Location.X=264|Location.Y=482|Color=8388608|FontID=1|IsHidden=T|Text=Rectangular|Name=Construction
|RECORD=41|OwnerIndex=1944|IndexInSheet=14|OwnerPartId=-1|Location.X=264|Location.Y=482|Color=8388608|FontID=1|IsHidden=T|Text=0.016inch|Name=Height
|RECORD=41|OwnerIndex=1944|IndexInSheet=15|OwnerPartId=-1|Location.X=264|Location.Y=482|Color=8388608|FontID=1|IsHidden=T|Text=0402|Name=Size Code
|RECORD=41|OwnerIndex=1944|IndexInSheet=16|OwnerPartId=-1|Location.X=264|Location.Y=482|Color=8388608|FontID=1|IsHidden=T|Text=Lead Free|Name=Lead Free
|RECORD=41|OwnerIndex=1944|IndexInSheet=17|OwnerPartId=-1|Location.X=264|Location.Y=482|Color=8388608|FontID=1|IsHidden=T|Text=No|Name=Radiation Hardening
|RECORD=41|OwnerIndex=1944|IndexInSheet=18|OwnerPartId=-1|Location.X=264|Location.Y=482|Color=8388608|FontID=1|IsHidden=T|Text=1%|Name=Tolerance
|RECORD=41|OwnerIndex=1944|IndexInSheet=19|OwnerPartId=-1|Location.X=264|Location.Y=482|Color=8388608|FontID=1|IsHidden=T|Text=0.02inch|Name=Width
|RECORD=41|OwnerIndex=1944|IndexInSheet=20|OwnerPartId=-1|Location.X=264|Location.Y=482|Color=8388608|FontID=1|IsHidden=T|Text=1kR|Name=Resistance
|RECORD=41|OwnerIndex=1944|IndexInSheet=21|OwnerPartId=-1|Location.X=264|Location.Y=482|Color=8388608|FontID=1|IsHidden=T|Text=Not|Name=Military Standard
|RECORD=41|OwnerIndex=1944|IndexInSheet=22|OwnerPartId=-1|Location.X=264|Location.Y=482|Color=8388608|FontID=1|IsHidden=T|Text=Thick Film|Name=Resistor Type
|RECORD=41|OwnerIndex=1944|IndexInSheet=23|OwnerPartId=-1|Location.X=264|Location.Y=482|Color=8388608|FontID=1|IsHidden=T|Text=100ppm/°C|Name=Temperature Coefficient
|RECORD=41|OwnerIndex=1944|IndexInSheet=24|OwnerPartId=-1|Location.X=264|Location.Y=482|Color=8388608|FontID=1|IsHidden=T|Text=2|Name=Number of Terminations
|RECORD=41|OwnerIndex=1944|IndexInSheet=25|OwnerPartId=-1|Location.X=264|Location.Y=482|Color=8388608|FontID=1|IsHidden=T|Text=-55°C|Name=Min Operating Temperature
|RECORD=41|OwnerIndex=1944|IndexInSheet=26|OwnerPartId=-1|Location.X=264|Location.Y=482|Color=8388608|FontID=1|IsHidden=T|Text=155°C|Name=Max Operating Temperature
|RECORD=41|OwnerIndex=1944|IndexInSheet=27|OwnerPartId=-1|Location.X=264|Location.Y=482|Color=8388608|FontID=1|IsHidden=T|Text=63mW|Name=Power Rating
|RECORD=41|OwnerIndex=1944|IndexInSheet=28|OwnerPartId=-1|Location.X=264|Location.Y=482|Color=8388608|FontID=1|IsHidden=T|Text=0.5mm|Name=Depth
|RECORD=41|OwnerIndex=1944|IndexInSheet=29|OwnerPartId=-1|Location.X=264|Location.Y=482|Color=8388608|FontID=1|IsHidden=T|Text=Automotive AEC-Q200|Name=Features
|RECORD=41|OwnerIndex=1944|IndexInSheet=30|OwnerPartId=-1|Location.X=264|Location.Y=482|Color=8388608|FontID=1|IsHidden=T|Text=Tape and Reel|Name=Packaging
|RECORD=41|OwnerIndex=1944|IndexInSheet=31|OwnerPartId=-1|Location.X=264|Location.Y=482|Color=8388608|FontID=1|IsHidden=T|Text=1005|Name=Case Code (Metric)
|RECORD=41|OwnerIndex=1944|IndexInSheet=32|OwnerPartId=-1|Location.X=264|Location.Y=482|Color=8388608|FontID=1|IsHidden=T|Text=Surface Mount|Name=Mount
|RECORD=41|OwnerIndex=1944|IndexInSheet=33|OwnerPartId=-1|Location.X=264|Location.Y=482|Color=8388608|FontID=1|IsHidden=T|Text=Tin|Name=Contact Plating
|RECORD=41|OwnerIndex=1944|IndexInSheet=34|OwnerPartId=-1|Location.X=264|Location.Y=482|Color=8388608|FontID=1|IsHidden=T|Text=63mW|Name=Max Power Dissipation
|RECORD=41|OwnerIndex=1944|IndexInSheet=35|OwnerPartId=-1|Location.X=264|Location.Y=482|Color=8388608|FontID=1|IsHidden=T|Text=0402|Name=Case/Package
|RECORD=41|OwnerIndex=1944|IndexInSheet=36|OwnerPartId=-1|Location.X=264|Location.Y=482|Color=8388608|FontID=1|IsHidden=T|Text=0402|Name=Case Code (Imperial)
|RECORD=41|OwnerIndex=1944|IndexInSheet=37|OwnerPartId=-1|Location.X=264|Location.Y=482|Color=8388608|FontID=1|IsHidden=T|Text=RMCF|Name=Series
|RECORD=34|OwnerIndex=1944|IndexInSheet=-1|OwnerPartId=-1|Location.X=276|Location.Y=454|Color=8388608|FontID=1|Text=R2|Name=Designator|ReadOnlyState=1
|RECORD=41|OwnerIndex=1944|IndexInSheet=-1|OwnerPartId=1|Location.X=276|Location.Y=444|Color=8388608|FontID=1|Text=1k|Name=Comment
|RECORD=44|OwnerIndex=1944
|RECORD=45|OwnerIndex=1987|IndexInSheet=-1|UseComponentLibrary=T|ModelName=FP-RMCF0402-MFG|ModelType=PCBLIB|DatafileCount=1|ModelDatafileEntity0=FP-RMCF0402-MFG|ModelDatafileKind0=PCBLib|IsCurrent=T|DatalinksLocked=T|DatabaseDatalinksLocked=T
|RECORD=46|OwnerIndex=1988
|RECORD=48|OwnerIndex=1988
|RECORD=45|OwnerIndex=1987|IndexInSheet=-1|UseComponentLibrary=T|ModelName=FP-RMCF0402-IPC_C|ModelType=PCBLIB|DatafileCount=1|ModelDatafileEntity0=FP-RMCF0402-IPC_C|ModelDatafileKind0=PCBLib|DatalinksLocked=T|DatabaseDatalinksLocked=T
|RECORD=46|OwnerIndex=1991
|RECORD=48|OwnerIndex=1991
|RECORD=45|OwnerIndex=1987|IndexInSheet=-1|UseComponentLibrary=T|ModelName=FP-RMCF0402-IPC_B|ModelType=PCBLIB|DatafileCount=1|ModelDatafileEntity0=FP-RMCF0402-IPC_B|ModelDatafileKind0=PCBLib|DatalinksLocked=T|DatabaseDatalinksLocked=T
|RECORD=46|OwnerIndex=1994
|RECORD=48|OwnerIndex=1994
|RECORD=45|OwnerIndex=1987|IndexInSheet=-1|UseComponentLibrary=T|ModelName=FP-RMCF0402-IPC_A|ModelType=PCBLIB|DatafileCount=1|ModelDatafileEntity0=FP-RMCF0402-IPC_A|ModelDatafileKind0=PCBLib|DatalinksLocked=T|DatabaseDatalinksLocked=T
|RECORD=46|OwnerIndex=1997
|RECORD=48|OwnerIndex=1997
|RECORD=17|IndexInSheet=131|OwnerPartId=-1|Style=2|ShowNetName=T|Location.X=270|Location.Y=480|Orientation=1|Color=128|FontID=1|Text=VCC
|RECORD=25|IndexInSheet=132|OwnerPartId=-1|Location.X=300|Location.Y=410|Justification=2|Color=128|FontID=1|Text=RXD
|RECORD=17|IndexInSheet=133|OwnerPartId=-1|Style=2|ShowNetName=T|Location.X=380|Location.Y=480|Orientation=1|Color=128|FontID=1|Text=VCC
|RECORD=1|LibReference=1029c3af85768c4190bb7ad29bc67b5|ComponentDescription=1kO ±1% 0.063W 0402 Thick Film Chip Resistor AEC-Q200 compliant|PartCount=2|DisplayModeCount=1|IndexInSheet=134|OwnerPartId=-1|Location.X=380|Location.Y=410|Orientation=1|CurrentPartId=1|LibraryPath=*|SourceLibraryName=Altium Content Vault|TargetFileName=*|AreaColor=11599871|Color=128|PartIDLocked=T|DesignItemId=CMP-26527-000026-1|AllPinCount=2
|RECORD=2|OwnerIndex=2003|OwnerPartId=1|Electrical=4|PinConglomerate=35|PinLength=20|Location.X=380|Location.Y=430|Name=1|Designator=1|PinPropagationDelay=0.000000E+000
|RECORD=2|OwnerIndex=2003|OwnerPartId=1|Electrical=4|PinConglomerate=33|PinLength=20|Location.X=380|Location.Y=460|Name=2|Designator=2|PinPropagationDelay=0.000000E+000
|RECORD=13|OwnerIndex=2003|IsNotAccesible=T|IndexInSheet=2|OwnerPartId=1|Location.X=380|Location.Y=430|Corner.X=375|Corner.Y=433|LineWidth=1|Color=16711680
|RECORD=13|OwnerIndex=2003|IsNotAccesible=T|IndexInSheet=3|OwnerPartId=1|Location.X=375|Location.Y=433|Corner.X=385|Corner.Y=438|LineWidth=1|Color=16711680
|RECORD=13|OwnerIndex=2003|IsNotAccesible=T|IndexInSheet=4|OwnerPartId=1|Location.X=385|Location.Y=438|Corner.X=375|Corner.Y=443|LineWidth=1|Color=16711680
|RECORD=13|OwnerIndex=2003|IsNotAccesible=T|IndexInSheet=5|OwnerPartId=1|Location.X=375|Location.Y=443|Corner.X=385|Corner.Y=448|LineWidth=1|Color=16711680
|RECORD=13|OwnerIndex=2003|IsNotAccesible=T|IndexInSheet=6|OwnerPartId=1|Location.X=385|Location.Y=448|Corner.X=375|Corner.Y=453|LineWidth=1|Color=16711680
|RECORD=13|OwnerIndex=2003|IsNotAccesible=T|IndexInSheet=7|OwnerPartId=1|Location.X=375|Location.Y=453|Corner.X=385|Corner.Y=458|LineWidth=1|Color=16711680
|RECORD=13|OwnerIndex=2003|IsNotAccesible=T|IndexInSheet=8|OwnerPartId=1|Location.X=385|Location.Y=458|Corner.X=380|Corner.Y=460|LineWidth=1|Color=16711680
|RECORD=13|OwnerIndex=2003|IsNotAccesible=T|IndexInSheet=9|OwnerPartId=1|Location.X=380|Location.Y=430|Corner.X=380|Corner.Y=427|LineWidth=1|Color=16711680
|RECORD=13|OwnerIndex=2003|IsNotAccesible=T|IndexInSheet=10|OwnerPartId=1|Location.X=380|Location.Y=460|Corner.X=380|Corner.Y=463|LineWidth=1|Color=16711680
|RECORD=41|OwnerIndex=2003|IndexInSheet=11|OwnerPartId=-1|Location.X=374|Location.Y=482|Color=8388608|FontID=1|IsHidden=T|Text=1mm|Name=Length
|RECORD=41|OwnerIndex=2003|IndexInSheet=12|OwnerPartId=-1|Location.X=374|Location.Y=482|Color=8388608|FontID=1|IsHidden=T|Text=Yes|Name=RoHS Compliant
|RECORD=41|OwnerIndex=2003|IndexInSheet=13|OwnerPartId=-1|Location.X=374|Location.Y=482|Color=8388608|FontID=1|IsHidden=T|Text=Rectangular|Name=Construction
|RECORD=41|OwnerIndex=2003|IndexInSheet=14|OwnerPartId=-1|Location.X=374|Location.Y=482|Color=8388608|FontID=1|IsHidden=T|Text=0.016inch|Name=Height
|RECORD=41|OwnerIndex=2003|IndexInSheet=15|OwnerPartId=-1|Location.X=374|Location.Y=482|Color=8388608|FontID=1|IsHidden=T|Text=0402|Name=Size Code
|RECORD=41|OwnerIndex=2003|IndexInSheet=16|OwnerPartId=-1|Location.X=374|Location.Y=482|Color=8388608|FontID=1|IsHidden=T|Text=Lead Free|Name=Lead Free
|RECORD=41|OwnerIndex=2003|IndexInSheet=17|OwnerPartId=-1|Location.X=374|Location.Y=482|Color=8388608|FontID=1|IsHidden=T|Text=No|Name=Radiation Hardening
|RECORD=41|OwnerIndex=2003|IndexInSheet=18|OwnerPartId=-1|Location.X=374|Location.Y=482|Color=8388608|FontID=1|IsHidden=T|Text=1%|Name=Tolerance
|RECORD=41|OwnerIndex=2003|IndexInSheet=19|OwnerPartId=-1|Location.X=374|Location.Y=482|Color=8388608|FontID=1|IsHidden=T|Text=0.02inch|Name=Width
|RECORD=41|OwnerIndex=2003|IndexInSheet=20|OwnerPartId=-1|Location.X=374|Location.Y=482|Color=8388608|FontID=1|IsHidden=T|Text=1kR|Name=Resistance
|RECORD=41|OwnerIndex=2003|IndexInSheet=21|OwnerPartId=-1|Location.X=374|Location.Y=482|Color=8388608|FontID=1|IsHidden=T|Text=Not|Name=Military Standard
|RECORD=41|OwnerIndex=2003|IndexInSheet=22|OwnerPartId=-1|Location.X=374|Location.Y=482|Color=8388608|FontID=1|IsHidden=T|Text=Thick Film|Name=Resistor Type
|RECORD=41|OwnerIndex=2003|IndexInSheet=23|OwnerPartId=-1|Location.X=374|Location.Y=482|Color=8388608|FontID=1|IsHidden=T|Text=100ppm/°C|Name=Temperature Coefficient
|RECORD=41|OwnerIndex=2003|IndexInSheet=24|OwnerPartId=-1|Location.X=374|Location.Y=482|Color=8388608|FontID=1|IsHidden=T|Text=2|Name=Number of Terminations
|RECORD=41|OwnerIndex=2003|IndexInSheet=25|OwnerPartId=-1|Location.X=374|Location.Y=482|Color=8388608|FontID=1|IsHidden=T|Text=-55°C|Name=Min Operating Temperature
|RECORD=41|OwnerIndex=2003|IndexInSheet=26|OwnerPartId=-1|Location.X=374|Location.Y=482|Color=8388608|FontID=1|IsHidden=T|Text=155°C|Name=Max Operating Temperature
|RECORD=41|OwnerIndex=2003|IndexInSheet=27|OwnerPartId=-1|Location.X=374|Location.Y=482|Color=8388608|FontID=1|IsHidden=T|Text=63mW|Name=Power Rating
|RECORD=41|OwnerIndex=2003|IndexInSheet=28|OwnerPartId=-1|Location.X=374|Location.Y=482|Color=8388608|FontID=1|IsHidden=T|Text=0.5mm|Name=Depth
|RECORD=41|OwnerIndex=2003|IndexInSheet=29|OwnerPartId=-1|Location.X=374|Location.Y=482|Color=8388608|FontID=1|IsHidden=T|Text=Automotive AEC-Q200|Name=Features
|RECORD=41|OwnerIndex=2003|IndexInSheet=30|OwnerPartId=-1|Location.X=374|Location.Y=482|Color=8388608|FontID=1|IsHidden=T|Text=Tape and Reel|Name=Packaging
|RECORD=41|OwnerIndex=2003|IndexInSheet=31|OwnerPartId=-1|Location.X=374|Location.Y=482|Color=8388608|FontID=1|IsHidden=T|Text=1005|Name=Case Code (Metric)
|RECORD=41|OwnerIndex=2003|IndexInSheet=32|OwnerPartId=-1|Location.X=374|Location.Y=482|Color=8388608|FontID=1|IsHidden=T|Text=Surface Mount|Name=Mount
|RECORD=41|OwnerIndex=2003|IndexInSheet=33|OwnerPartId=-1|Location.X=374|Location.Y=482|Color=8388608|FontID=1|IsHidden=T|Text=Tin|Name=Contact Plating
|RECORD=41|OwnerIndex=2003|IndexInSheet=34|OwnerPartId=-1|Location.X=374|Location.Y=482|Color=8388608|FontID=1|IsHidden=T|Text=63mW|Name=Max Power Dissipation
|RECORD=41|OwnerIndex=2003|IndexInSheet=35|OwnerPartId=-1|Location.X=374|Location.Y=482|Color=8388608|FontID=1|IsHidden=T|Text=0402|Name=Case/Package
|RECORD=41|OwnerIndex=2003|IndexInSheet=36|OwnerPartId=-1|Location.X=374|Location.Y=482|Color=8388608|FontID=1|IsHidden=T|Text=0402|Name=Case Code (Imperial)
|RECORD=41|OwnerIndex=2003|IndexInSheet=37|OwnerPartId=-1|Location.X=374|Location.Y=482|Color=8388608|FontID=1|IsHidden=T|Text=RMCF|Name=Series
|RECORD=34|OwnerIndex=2003|IndexInSheet=-1|OwnerPartId=-1|Location.X=386|Location.Y=454|Color=8388608|FontID=1|Text=R3|Name=Designator|ReadOnlyState=1
|RECORD=41|OwnerIndex=2003|IndexInSheet=-1|OwnerPartId=1|Location.X=386|Location.Y=444|Color=8388608|FontID=1|Text=1k|Name=Comment
|RECORD=44|OwnerIndex=2003
|RECORD=45|OwnerIndex=2046|IndexInSheet=-1|UseComponentLibrary=T|ModelName=FP-RMCF0402-MFG|ModelType=PCBLIB|DatafileCount=1|ModelDatafileEntity0=FP-RMCF0402-MFG|ModelDatafileKind0=PCBLib|IsCurrent=T|DatalinksLocked=T|DatabaseDatalinksLocked=T
|RECORD=46|OwnerIndex=2047
|RECORD=48|OwnerIndex=2047
|RECORD=45|OwnerIndex=2046|IndexInSheet=-1|UseComponentLibrary=T|ModelName=FP-RMCF0402-IPC_C|ModelType=PCBLIB|DatafileCount=1|ModelDatafileEntity0=FP-RMCF0402-IPC_C|ModelDatafileKind0=PCBLib|DatalinksLocked=T|DatabaseDatalinksLocked=T
|RECORD=46|OwnerIndex=2050
|RECORD=48|OwnerIndex=2050
|RECORD=45|OwnerIndex=2046|IndexInSheet=-1|UseComponentLibrary=T|ModelName=FP-RMCF0402-IPC_B|ModelType=PCBLIB|DatafileCount=1|ModelDatafileEntity0=FP-RMCF0402-IPC_B|ModelDatafileKind0=PCBLib|DatalinksLocked=T|DatabaseDatalinksLocked=T
|RECORD=46|OwnerIndex=2053
|RECORD=48|OwnerIndex=2053
|RECORD=45|OwnerIndex=2046|IndexInSheet=-1|UseComponentLibrary=T|ModelName=FP-RMCF0402-IPC_A|ModelType=PCBLIB|DatafileCount=1|ModelDatafileEntity0=FP-RMCF0402-IPC_A|ModelDatafileKind0=PCBLib|DatalinksLocked=T|DatabaseDatalinksLocked=T
|RECORD=46|OwnerIndex=2056
|RECORD=48|OwnerIndex=2056
|RECORD=25|IndexInSheet=135|OwnerPartId=-1|Location.X=430|Location.Y=410|Justification=2|Color=128|FontID=1|Text=TXD_OUT
|RECORD=14|IndexInSheet=136|OwnerPartId=-1|Location.X=240|Location.Y=390|Corner.X=440|Corner.Y=510|Color=128|AreaColor=11599871
|RECORD=4|IndexInSheet=137|OwnerPartId=-1|Location.X=240|Location.Y=510|Color=8388608|FontID=15|Text=Buffer Pullups
|RECORD=27|IndexInSheet=138|OwnerPartId=-1|LineWidth=1|Color=8388608|LocationCount=2|X1=60|Y1=600|X2=90|Y2=600
|RECORD=27|IndexInSheet=139|OwnerPartId=-1|LineWidth=1|Color=8388608|LocationCount=2|X1=60|Y1=590|X2=90|Y2=590
|RECORD=27|IndexInSheet=140|OwnerPartId=-1|LineWidth=1|Color=8388608|LocationCount=2|X1=190|Y1=590|X2=160|Y2=590
|RECORD=27|IndexInSheet=141|OwnerPartId=-1|LineWidth=1|Color=8388608|LocationCount=2|X1=60|Y1=580|X2=90|Y2=580
|RECORD=27|IndexInSheet=142|OwnerPartId=-1|LineWidth=1|Color=8388608|LocationCount=2|X1=190|Y1=580|X2=160|Y2=580
|RECORD=27|IndexInSheet=143|OwnerPartId=-1|LineWidth=1|Color=8388608|LocationCount=2|X1=60|Y1=570|X2=90|Y2=570
|RECORD=27|IndexInSheet=144|OwnerPartId=-1|LineWidth=1|Color=8388608|LocationCount=2|X1=200|Y1=570|X2=160|Y2=570
|RECORD=27|IndexInSheet=145|OwnerPartId=-1|LineWidth=1|Color=8388608|LocationCount=2|X1=190|Y1=600|X2=160|Y2=600
|RECORD=27|IndexInSheet=146|OwnerPartId=-1|LineWidth=1|Color=8388608|LocationCount=2|X1=40|Y1=470|X2=90|Y2=470
|RECORD=27|IndexInSheet=147|OwnerPartId=-1|LineWidth=1|Color=8388608|LocationCount=2|X1=220|Y1=400|X2=160|Y2=400
|RECORD=27|IndexInSheet=148|OwnerPartId=-1|LineWidth=1|Color=8388608|LocationCount=2|X1=40|Y1=400|X2=90|Y2=400
|RECORD=27|IndexInSheet=149|OwnerPartId=-1|LineWidth=1|Color=8388608|LocationCount=2|X1=220|Y1=470|X2=160|Y2=470
|RECORD=27|IndexInSheet=150|OwnerPartId=-1|LineWidth=1|Color=8388608|LocationCount=2|X1=70|Y1=270|X2=90|Y2=270
|RECORD=27|IndexInSheet=151|OwnerPartId=-1|LineWidth=1|Color=8388608|LocationCount=2|X1=670|Y1=590|X2=700|Y2=590
|RECORD=27|IndexInSheet=152|OwnerPartId=-1|LineWidth=1|Color=8388608|LocationCount=4|X1=600|Y1=660|X2=650|Y2=660|X3=700|Y3=660|X4=700|Y4=610
|RECORD=27|IndexInSheet=153|OwnerPartId=-1|LineWidth=1|Color=8388608|LocationCount=2|X1=700|Y1=600|X2=700|Y2=610
|RECORD=27|IndexInSheet=154|OwnerPartId=-1|LineWidth=1|Color=8388608|LocationCount=9|X1=860|Y1=610|X2=860|Y2=600|X3=860|Y3=590|X4=860|Y4=580|X5=860|Y5=570|X6=860|Y6=560|X7=860|Y7=550|X8=860|Y8=540|X9=860|Y9=530
|RECORD=27|IndexInSheet=155|OwnerPartId=-1|LineWidth=1|Color=8388608|LocationCount=3|X1=700|Y1=570|X2=650|Y2=570|X3=600|Y3=570
|RECORD=27|IndexInSheet=156|OwnerPartId=-1|LineWidth=1|Color=8388608|LocationCount=3|X1=700|Y1=550|X2=680|Y2=550|X3=680|Y3=520
|RECORD=27|IndexInSheet=157|OwnerPartId=-1|LineWidth=1|Color=8388608|LocationCount=2|X1=890|Y1=430|X2=850|Y2=430
|RECORD=27|IndexInSheet=158|OwnerPartId=-1|LineWidth=1|Color=8388608|LocationCount=2|X1=890|Y1=420|X2=850|Y2=420
|RECORD=27|IndexInSheet=159|OwnerPartId=-1|LineWidth=1|Color=8388608|LocationCount=2|X1=680|Y1=380|X2=700|Y2=380
|RECORD=27|IndexInSheet=160|OwnerPartId=-1|LineWidth=1|Color=8388608|LocationCount=2|X1=680|Y1=370|X2=700|Y2=370
|RECORD=27|IndexInSheet=161|OwnerPartId=-1|LineWidth=1|Color=8388608|LocationCount=2|X1=620|Y1=430|X2=700|Y2=430
|RECORD=27|IndexInSheet=162|OwnerPartId=-1|LineWidth=1|Color=8388608|LocationCount=2|X1=670|Y1=220|X2=700|Y2=220
|RECORD=27|IndexInSheet=163|OwnerPartId=-1|LineWidth=1|Color=8388608|LocationCount=2|X1=630|Y1=180|X2=700|Y2=180
|RECORD=27|IndexInSheet=164|OwnerPartId=-1|LineWidth=1|Color=8388608|LocationCount=2|X1=630|Y1=190|X2=700|Y2=190
|RECORD=27|IndexInSheet=165|OwnerPartId=-1|LineWidth=1|Color=8388608|LocationCount=2|X1=630|Y1=170|X2=700|Y2=170
|RECORD=27|IndexInSheet=166|OwnerPartId=-1|LineWidth=1|Color=8388608|LocationCount=2|X1=620|Y1=430|X2=620|Y2=420
|RECORD=27|IndexInSheet=167|OwnerPartId=-1|LineWidth=1|Color=8388608|LocationCount=2|X1=260|Y1=160|X2=300|Y2=160
|RECORD=27|IndexInSheet=168|OwnerPartId=-1|LineWidth=1|Color=8388608|LocationCount=2|X1=420|Y1=160|X2=370|Y2=160
|RECORD=27|IndexInSheet=169|OwnerPartId=-1|LineWidth=1|Color=8388608|LocationCount=2|X1=260|Y1=100|X2=300|Y2=100
|RECORD=27|IndexInSheet=170|OwnerPartId=-1|LineWidth=1|Color=8388608|LocationCount=2|X1=420|Y1=100|X2=370|Y2=100
|RECORD=27|IndexInSheet=171|OwnerPartId=-1|LineWidth=1|Color=8388608|LocationCount=2|X1=300|Y1=350|X2=270|Y2=350
|RECORD=27|IndexInSheet=172|OwnerPartId=-1|LineWidth=1|Color=8388608|LocationCount=2|X1=300|Y1=410|X2=270|Y2=410
|RECORD=27|IndexInSheet=173|OwnerPartId=-1|LineWidth=1|Color=8388608|LocationCount=2|X1=430|Y1=410|X2=380|Y2=410
|RECORD=29|IndexInSheet=-1|OwnerPartId=-1|Location.X=70|Location.Y=270|Color=128
|RECORD=29|IndexInSheet=-1|OwnerPartId=-1|Location.X=600|Location.Y=570|Color=128
|RECORD=29|IndexInSheet=-1|OwnerPartId=-1|Location.X=600|Location.Y=660|Color=128
|RECORD=29|IndexInSheet=-1|OwnerPartId=-1|Location.X=620|Location.Y=430|Color=128
|RECORD=29|IndexInSheet=-1|OwnerPartId=-1|Location.X=650|Location.Y=570|Color=128
|RECORD=29|IndexInSheet=-1|OwnerPartId=-1|Location.X=650|Location.Y=660|Color=128
|RECORD=29|IndexInSheet=-1|OwnerPartId=-1|Location.X=700|Location.Y=610|Color=128
|RECORD=29|IndexInSheet=-1|OwnerPartId=-1|Location.X=860|Location.Y=530|Color=128
|RECORD=29|IndexInSheet=-1|OwnerPartId=-1|Location.X=860|Location.Y=540|Color=128
|RECORD=29|IndexInSheet=-1|OwnerPartId=-1|Location.X=860|Location.Y=550|Color=128
|RECORD=29|IndexInSheet=-1|OwnerPartId=-1|Location.X=860|Location.Y=560|Color=128
|RECORD=29|IndexInSheet=-1|OwnerPartId=-1|Location.X=860|Location.Y=570|Color=128
|RECORD=29|IndexInSheet=-1|OwnerPartId=-1|Location.X=860|Location.Y=580|Color=128
|RECORD=29|IndexInSheet=-1|OwnerPartId=-1|Location.X=860|Location.Y=590|Color=128
|RECORD=29|IndexInSheet=-1|OwnerPartId=-1|Location.X=860|Location.Y=600|Color=128